FILE_TYPE = MACRO_DRAWING;
SET COLOR_WIRE YELLOW;
SET COLOR_PROP ORANGE;
SET COLOR_DOT WHITE;
SET COLOR_ARC YELLOW;
SET COLOR_BODY GREEN;
SET COLOR_NOTE PURPLE;
SET PROP_DISPLAY VALUE;
SET PAGE_NUMBER P69;
FORCEADD Q_CAP..1
(-9075 875);
FORCEPROP 1 LAST LOCATION C3925
J 0
(-9025 975);
DISPLAY 0.489362 (-9025 975);
PAINT SKYBLUE (-9025 975);
FORCEPROP 2 LAST $SEC 1
J 0
(-9025 1075);
DISPLAY 0.680851 (-9025 1075);
PAINT MONO (-9025 1075);
DISPLAY INVISIBLE (-9025 1075);
FORCEPROP 2 LAST CDS_SEC 1
J 0
(-9025 1075);
DISPLAY 1.021277 (-9025 1075);
DISPLAY INVISIBLE (-9025 1075);
FORCEPROP 1 LASTPIN (-9075 975) $PN 1
J 0
(-9065 955);
DISPLAY 0.489362 (-9065 955);
FORCEPROP 1 LASTPIN (-9075 775) $PN 2
J 0
(-9065 755);
DISPLAY 0.489362 (-9065 755);
FORCEPROP 1 LAST MATERIAL X6S
J 0
(-9025 775);
DISPLAY 0.489362 (-9025 775);
PAINT SKYBLUE (-9025 775);
FORCEPROP 1 LAST TOLERANCE 20%
J 0
(-9025 825);
DISPLAY 0.489362 (-9025 825);
PAINT SKYBLUE (-9025 825);
FORCEPROP 1 LAST VALUE 22UF
J 0
(-9025 925);
DISPLAY 0.489362 (-9025 925);
PAINT SKYBLUE (-9025 925);
FORCEPROP 1 LAST VOLTAGE 4V
J 0
(-9025 875);
DISPLAY 0.489362 (-9025 875);
PAINT SKYBLUE (-9025 875);
FORCEPROP 1 LAST PACK_TYPE C0402
J 0
(-9025 675);
DISPLAY 0.489362 (-9025 675);
PAINT SKYBLUE (-9025 675);
FORCEPROP 2 LAST CDS_LIB pure_quanta
J 0
(-9075 875);
PAINT MONO (-9075 875);
DISPLAY INVISIBLE (-9075 875);
FORCEPROP 1 LAST PATH I1
J 0
(-9025 1025);
DISPLAY 0.978723 (-9025 1025);
PAINT WHITE (-9025 1025);
DISPLAY INVISIBLE (-9025 1025);
FORCEPROP 1 LAST PART_NUMBER CH622KMEB02
J 0
(-9025 725);
DISPLAY 0.489362 (-9025 725);
PAINT SKYBLUE (-9025 725);
DISPLAY INVISIBLE (-9025 725);
FORCEADD Q_CAP..1
(-8625 2300);
FORCEPROP 1 LAST LOCATION C2539
J 0
(-8575 2400);
DISPLAY 0.489362 (-8575 2400);
PAINT SKYBLUE (-8575 2400);
FORCEPROP 2 LAST $SEC 1
J 0
(-8575 2500);
DISPLAY 0.680851 (-8575 2500);
PAINT MONO (-8575 2500);
DISPLAY INVISIBLE (-8575 2500);
FORCEPROP 2 LAST CDS_SEC 1
J 0
(-8575 2500);
DISPLAY 1.021277 (-8575 2500);
DISPLAY INVISIBLE (-8575 2500);
FORCEPROP 1 LASTPIN (-8625 2400) $PN 1
J 0
(-8615 2380);
DISPLAY 0.489362 (-8615 2380);
FORCEPROP 1 LASTPIN (-8625 2200) $PN 2
J 0
(-8615 2180);
DISPLAY 0.489362 (-8615 2180);
FORCEPROP 1 LAST MATERIAL X6S
J 0
(-8575 2200);
DISPLAY 0.489362 (-8575 2200);
PAINT SKYBLUE (-8575 2200);
FORCEPROP 1 LAST TOLERANCE 20%
J 0
(-8575 2250);
DISPLAY 0.489362 (-8575 2250);
PAINT SKYBLUE (-8575 2250);
FORCEPROP 1 LAST VALUE 22UF
J 0
(-8575 2350);
DISPLAY 0.489362 (-8575 2350);
PAINT SKYBLUE (-8575 2350);
FORCEPROP 1 LAST VOLTAGE 4V
J 0
(-8575 2300);
DISPLAY 0.489362 (-8575 2300);
PAINT SKYBLUE (-8575 2300);
FORCEPROP 1 LAST PACK_TYPE C0402
J 0
(-8575 2100);
DISPLAY 0.489362 (-8575 2100);
PAINT SKYBLUE (-8575 2100);
FORCEPROP 2 LAST CDS_LIB pure_quanta
J 0
(-8625 2300);
PAINT MONO (-8625 2300);
DISPLAY INVISIBLE (-8625 2300);
FORCEPROP 1 LAST PATH I10
J 0
(-8575 2450);
DISPLAY 0.978723 (-8575 2450);
PAINT WHITE (-8575 2450);
DISPLAY INVISIBLE (-8575 2450);
FORCEPROP 1 LAST PART_NUMBER CH622KMEB02
J 0
(-8575 2150);
DISPLAY 0.489362 (-8575 2150);
PAINT SKYBLUE (-8575 2150);
DISPLAY INVISIBLE (-8575 2150);
FORCEADD UNIVERSAL_GND..1
(-5100 4775);
FORCEPROP 3 LASTPIN (-5100 4825) SIG_NAME GND\g
J 0
(-5090 4835);
DISPLAY 0.659574 (-5090 4835);
PAINT MONO (-5090 4835);
DISPLAY INVISIBLE (-5090 4835);
FORCEPROP 2 LAST CDS_LIB pure_quanta_power
J 0
(-5100 4775);
PAINT MONO (-5100 4775);
DISPLAY INVISIBLE (-5100 4775);
FORCEPROP 1 LAST HDL_POWER GND
J 1
(-5075 4700);
DISPLAY 0.872340 (-5075 4700);
PAINT GREEN (-5075 4700);
DISPLAY INVISIBLE (-5075 4700);
FORCEPROP 1 LAST PATH I100
J 0
(-5025 4775);
DISPLAY 0.872340 (-5025 4775);
PAINT AQUA (-5025 4775);
DISPLAY INVISIBLE (-5025 4775);
FORCEADD Q_CAP..1
(-5100 5150);
FORCEPROP 1 LAST LOCATION C2591
J 0
(-5050 5250);
DISPLAY 0.489362 (-5050 5250);
PAINT SKYBLUE (-5050 5250);
FORCEPROP 2 LAST $SEC 1
J 0
(-5050 5350);
DISPLAY 0.680851 (-5050 5350);
PAINT MONO (-5050 5350);
DISPLAY INVISIBLE (-5050 5350);
FORCEPROP 2 LAST CDS_SEC 1
J 0
(-5050 5350);
DISPLAY 1.021277 (-5050 5350);
DISPLAY INVISIBLE (-5050 5350);
FORCEPROP 1 LASTPIN (-5100 5250) $PN 1
J 0
(-5090 5230);
DISPLAY 0.489362 (-5090 5230);
FORCEPROP 1 LASTPIN (-5100 5050) $PN 2
J 0
(-5090 5030);
DISPLAY 0.489362 (-5090 5030);
FORCEPROP 1 LAST MATERIAL X6S
J 0
(-5050 5050);
DISPLAY 0.489362 (-5050 5050);
PAINT SKYBLUE (-5050 5050);
FORCEPROP 1 LAST TOLERANCE 20%
J 0
(-5050 5100);
DISPLAY 0.489362 (-5050 5100);
PAINT SKYBLUE (-5050 5100);
FORCEPROP 1 LAST VALUE 22UF
J 0
(-5050 5200);
DISPLAY 0.489362 (-5050 5200);
PAINT SKYBLUE (-5050 5200);
FORCEPROP 1 LAST VOLTAGE 4V
J 0
(-5050 5150);
DISPLAY 0.489362 (-5050 5150);
PAINT SKYBLUE (-5050 5150);
FORCEPROP 1 LAST PACK_TYPE C0402
J 0
(-5050 4950);
DISPLAY 0.489362 (-5050 4950);
PAINT SKYBLUE (-5050 4950);
FORCEPROP 2 LAST CDS_LIB pure_quanta
J 0
(-5100 5150);
PAINT MONO (-5100 5150);
DISPLAY INVISIBLE (-5100 5150);
FORCEPROP 1 LAST PATH I101
J 0
(-5050 5300);
DISPLAY 0.978723 (-5050 5300);
PAINT WHITE (-5050 5300);
DISPLAY INVISIBLE (-5050 5300);
FORCEPROP 1 LAST PART_NUMBER CH622KMEB02
J 0
(-5050 5000);
DISPLAY 0.489362 (-5050 5000);
PAINT SKYBLUE (-5050 5000);
DISPLAY INVISIBLE (-5050 5000);
FORCEADD Q_CAP..1
(-4500 4325);
FORCEPROP 1 LAST LOCATION C2599
J 0
(-4450 4425);
DISPLAY 0.489362 (-4450 4425);
PAINT SKYBLUE (-4450 4425);
FORCEPROP 2 LAST $SEC 1
J 0
(-4450 4525);
DISPLAY 0.680851 (-4450 4525);
PAINT MONO (-4450 4525);
DISPLAY INVISIBLE (-4450 4525);
FORCEPROP 2 LAST CDS_SEC 1
J 0
(-4450 4525);
DISPLAY 1.021277 (-4450 4525);
DISPLAY INVISIBLE (-4450 4525);
FORCEPROP 1 LASTPIN (-4500 4425) $PN 1
J 0
(-4490 4405);
DISPLAY 0.489362 (-4490 4405);
FORCEPROP 1 LASTPIN (-4500 4225) $PN 2
J 0
(-4490 4205);
DISPLAY 0.489362 (-4490 4205);
FORCEPROP 1 LAST MATERIAL X6S
J 0
(-4450 4225);
DISPLAY 0.489362 (-4450 4225);
PAINT SKYBLUE (-4450 4225);
FORCEPROP 1 LAST TOLERANCE 20%
J 0
(-4450 4275);
DISPLAY 0.489362 (-4450 4275);
PAINT SKYBLUE (-4450 4275);
FORCEPROP 1 LAST VALUE 22UF
J 0
(-4450 4375);
DISPLAY 0.489362 (-4450 4375);
PAINT SKYBLUE (-4450 4375);
FORCEPROP 1 LAST VOLTAGE 4V
J 0
(-4450 4325);
DISPLAY 0.489362 (-4450 4325);
PAINT SKYBLUE (-4450 4325);
FORCEPROP 1 LAST PACK_TYPE C0402
J 0
(-4450 4125);
DISPLAY 0.489362 (-4450 4125);
PAINT SKYBLUE (-4450 4125);
FORCEPROP 2 LAST CDS_LIB pure_quanta
J 0
(-4500 4325);
PAINT MONO (-4500 4325);
DISPLAY INVISIBLE (-4500 4325);
FORCEPROP 1 LAST PATH I102
J 0
(-4450 4475);
DISPLAY 0.978723 (-4450 4475);
PAINT WHITE (-4450 4475);
DISPLAY INVISIBLE (-4450 4475);
FORCEPROP 1 LAST PART_NUMBER CH622KMEB02
J 0
(-4450 4175);
DISPLAY 0.489362 (-4450 4175);
PAINT SKYBLUE (-4450 4175);
DISPLAY INVISIBLE (-4450 4175);
FORCEADD UNIVERSAL_POWER..1
(-4500 4600);
FORCEPROP 3 LASTPIN (-4500 4550) SIG_NAME PVDDIO_P0\g
J 0
(-4490 4560);
DISPLAY 0.659574 (-4490 4560);
PAINT MONO (-4490 4560);
DISPLAY INVISIBLE (-4490 4560);
FORCEPROP 1 LAST HDL_POWER PVDDIO_P0
J 1
(-4500 4650);
DISPLAY 0.489362 (-4500 4650);
PAINT GREEN (-4500 4650);
FORCEPROP 2 LAST CDS_LIB pure_quanta_power
J 0
(-4500 4600);
DISPLAY INVISIBLE (-4500 4600);
FORCEPROP 1 LAST PATH I103
J 0
(-4450 4625);
DISPLAY 0.872340 (-4450 4625);
PAINT AQUA (-4450 4625);
DISPLAY INVISIBLE (-4450 4625);
FORCEADD Q_CAP..1
(-4525 5100);
FORCEPROP 1 LAST LOCATION C2598
J 0
(-4475 5200);
DISPLAY 0.489362 (-4475 5200);
PAINT SKYBLUE (-4475 5200);
FORCEPROP 2 LAST $SEC 1
J 0
(-4475 5300);
DISPLAY 0.680851 (-4475 5300);
PAINT MONO (-4475 5300);
DISPLAY INVISIBLE (-4475 5300);
FORCEPROP 2 LAST CDS_SEC 1
J 0
(-4475 5300);
DISPLAY 1.021277 (-4475 5300);
DISPLAY INVISIBLE (-4475 5300);
FORCEPROP 1 LASTPIN (-4525 5200) $PN 1
J 0
(-4515 5180);
DISPLAY 0.489362 (-4515 5180);
FORCEPROP 1 LASTPIN (-4525 5000) $PN 2
J 0
(-4515 4980);
DISPLAY 0.489362 (-4515 4980);
FORCEPROP 1 LAST MATERIAL X6S
J 0
(-4475 5000);
DISPLAY 0.489362 (-4475 5000);
PAINT SKYBLUE (-4475 5000);
FORCEPROP 1 LAST TOLERANCE 20%
J 0
(-4475 5050);
DISPLAY 0.489362 (-4475 5050);
PAINT SKYBLUE (-4475 5050);
FORCEPROP 1 LAST VALUE 22UF
J 0
(-4475 5150);
DISPLAY 0.489362 (-4475 5150);
PAINT SKYBLUE (-4475 5150);
FORCEPROP 1 LAST VOLTAGE 4V
J 0
(-4475 5100);
DISPLAY 0.489362 (-4475 5100);
PAINT SKYBLUE (-4475 5100);
FORCEPROP 1 LAST PACK_TYPE C0402
J 0
(-4475 4900);
DISPLAY 0.489362 (-4475 4900);
PAINT SKYBLUE (-4475 4900);
FORCEPROP 2 LAST CDS_LIB pure_quanta
J 0
(-4525 5100);
PAINT MONO (-4525 5100);
DISPLAY INVISIBLE (-4525 5100);
FORCEPROP 1 LAST PATH I104
J 0
(-4475 5250);
DISPLAY 0.978723 (-4475 5250);
PAINT WHITE (-4475 5250);
DISPLAY INVISIBLE (-4475 5250);
FORCEPROP 1 LAST PART_NUMBER CH622KMEB02
J 0
(-4475 4950);
DISPLAY 0.489362 (-4475 4950);
PAINT SKYBLUE (-4475 4950);
DISPLAY INVISIBLE (-4475 4950);
FORCEADD UNIVERSAL_GND..1
(-5100 5525);
FORCEPROP 3 LASTPIN (-5100 5575) SIG_NAME GND\g
J 0
(-5090 5585);
DISPLAY 0.659574 (-5090 5585);
PAINT MONO (-5090 5585);
DISPLAY INVISIBLE (-5090 5585);
FORCEPROP 2 LAST CDS_LIB pure_quanta_power
J 0
(-5100 5525);
PAINT MONO (-5100 5525);
DISPLAY INVISIBLE (-5100 5525);
FORCEPROP 1 LAST HDL_POWER GND
J 1
(-5075 5450);
DISPLAY 0.872340 (-5075 5450);
PAINT GREEN (-5075 5450);
DISPLAY INVISIBLE (-5075 5450);
FORCEPROP 1 LAST PATH I105
J 0
(-5025 5525);
DISPLAY 0.872340 (-5025 5525);
PAINT AQUA (-5025 5525);
DISPLAY INVISIBLE (-5025 5525);
FORCEADD Q_CAP..1
(-5100 5900);
FORCEPROP 1 LAST LOCATION C2590
J 0
(-5050 6000);
DISPLAY 0.489362 (-5050 6000);
PAINT SKYBLUE (-5050 6000);
FORCEPROP 2 LAST $SEC 1
J 0
(-5050 6100);
DISPLAY 0.680851 (-5050 6100);
PAINT MONO (-5050 6100);
DISPLAY INVISIBLE (-5050 6100);
FORCEPROP 2 LAST CDS_SEC 1
J 0
(-5050 6100);
DISPLAY 1.021277 (-5050 6100);
DISPLAY INVISIBLE (-5050 6100);
FORCEPROP 1 LASTPIN (-5100 6000) $PN 1
J 0
(-5090 5980);
DISPLAY 0.489362 (-5090 5980);
FORCEPROP 1 LASTPIN (-5100 5800) $PN 2
J 0
(-5090 5780);
DISPLAY 0.489362 (-5090 5780);
FORCEPROP 1 LAST MATERIAL X6S
J 0
(-5050 5800);
DISPLAY 0.489362 (-5050 5800);
PAINT SKYBLUE (-5050 5800);
FORCEPROP 1 LAST TOLERANCE 20%
J 0
(-5050 5850);
DISPLAY 0.489362 (-5050 5850);
PAINT SKYBLUE (-5050 5850);
FORCEPROP 1 LAST VALUE 22UF
J 0
(-5050 5950);
DISPLAY 0.489362 (-5050 5950);
PAINT SKYBLUE (-5050 5950);
FORCEPROP 1 LAST VOLTAGE 4V
J 0
(-5050 5900);
DISPLAY 0.489362 (-5050 5900);
PAINT SKYBLUE (-5050 5900);
FORCEPROP 1 LAST PACK_TYPE C0402
J 0
(-5050 5700);
DISPLAY 0.489362 (-5050 5700);
PAINT SKYBLUE (-5050 5700);
FORCEPROP 2 LAST CDS_LIB pure_quanta
J 0
(-5100 5900);
PAINT MONO (-5100 5900);
DISPLAY INVISIBLE (-5100 5900);
FORCEPROP 1 LAST PATH I106
J 0
(-5050 6050);
DISPLAY 0.978723 (-5050 6050);
PAINT WHITE (-5050 6050);
DISPLAY INVISIBLE (-5050 6050);
FORCEPROP 1 LAST PART_NUMBER CH622KMEB02
J 0
(-5050 5750);
DISPLAY 0.489362 (-5050 5750);
PAINT SKYBLUE (-5050 5750);
DISPLAY INVISIBLE (-5050 5750);
FORCEADD UNIVERSAL_POWER..1
(-4525 5375);
FORCEPROP 3 LASTPIN (-4525 5325) SIG_NAME PVDDIO_P0\g
J 0
(-4515 5335);
DISPLAY 0.659574 (-4515 5335);
PAINT MONO (-4515 5335);
DISPLAY INVISIBLE (-4515 5335);
FORCEPROP 1 LAST HDL_POWER PVDDIO_P0
J 1
(-4525 5425);
DISPLAY 0.489362 (-4525 5425);
PAINT GREEN (-4525 5425);
FORCEPROP 2 LAST CDS_LIB pure_quanta_power
J 0
(-4525 5375);
DISPLAY INVISIBLE (-4525 5375);
FORCEPROP 1 LAST PATH I107
J 0
(-4475 5400);
DISPLAY 0.872340 (-4475 5400);
PAINT AQUA (-4475 5400);
DISPLAY INVISIBLE (-4475 5400);
FORCEADD Q_CAP..1
(-4525 5900);
FORCEPROP 1 LAST LOCATION C2597
J 0
(-4475 6000);
DISPLAY 0.489362 (-4475 6000);
PAINT SKYBLUE (-4475 6000);
FORCEPROP 2 LAST $SEC 1
J 0
(-4475 6100);
DISPLAY 0.680851 (-4475 6100);
PAINT MONO (-4475 6100);
DISPLAY INVISIBLE (-4475 6100);
FORCEPROP 2 LAST CDS_SEC 1
J 0
(-4475 6100);
DISPLAY 1.021277 (-4475 6100);
DISPLAY INVISIBLE (-4475 6100);
FORCEPROP 1 LASTPIN (-4525 6000) $PN 1
J 0
(-4515 5980);
DISPLAY 0.489362 (-4515 5980);
FORCEPROP 1 LASTPIN (-4525 5800) $PN 2
J 0
(-4515 5780);
DISPLAY 0.489362 (-4515 5780);
FORCEPROP 1 LAST MATERIAL X6S
J 0
(-4475 5800);
DISPLAY 0.489362 (-4475 5800);
PAINT SKYBLUE (-4475 5800);
FORCEPROP 1 LAST TOLERANCE 20%
J 0
(-4475 5850);
DISPLAY 0.489362 (-4475 5850);
PAINT SKYBLUE (-4475 5850);
FORCEPROP 1 LAST VALUE 22UF
J 0
(-4475 5950);
DISPLAY 0.489362 (-4475 5950);
PAINT SKYBLUE (-4475 5950);
FORCEPROP 1 LAST VOLTAGE 4V
J 0
(-4475 5900);
DISPLAY 0.489362 (-4475 5900);
PAINT SKYBLUE (-4475 5900);
FORCEPROP 1 LAST PACK_TYPE C0402
J 0
(-4475 5700);
DISPLAY 0.489362 (-4475 5700);
PAINT SKYBLUE (-4475 5700);
FORCEPROP 2 LAST CDS_LIB pure_quanta
J 0
(-4525 5900);
PAINT MONO (-4525 5900);
DISPLAY INVISIBLE (-4525 5900);
FORCEPROP 1 LAST PATH I108
J 0
(-4475 6050);
DISPLAY 0.978723 (-4475 6050);
PAINT WHITE (-4475 6050);
DISPLAY INVISIBLE (-4475 6050);
FORCEPROP 1 LAST PART_NUMBER CH622KMEB02
J 0
(-4475 5750);
DISPLAY 0.489362 (-4475 5750);
PAINT SKYBLUE (-4475 5750);
DISPLAY INVISIBLE (-4475 5750);
FORCEADD UNIVERSAL_POWER..1
(-4525 6175);
FORCEPROP 3 LASTPIN (-4525 6125) SIG_NAME PVDDIO_P0\g
J 0
(-4515 6135);
DISPLAY 0.659574 (-4515 6135);
PAINT MONO (-4515 6135);
DISPLAY INVISIBLE (-4515 6135);
FORCEPROP 1 LAST HDL_POWER PVDDIO_P0
J 1
(-4525 6225);
DISPLAY 0.489362 (-4525 6225);
PAINT GREEN (-4525 6225);
FORCEPROP 2 LAST CDS_LIB pure_quanta_power
J 0
(-4525 6175);
DISPLAY INVISIBLE (-4525 6175);
FORCEPROP 1 LAST PATH I109
J 0
(-4475 6200);
DISPLAY 0.872340 (-4475 6200);
PAINT AQUA (-4475 6200);
DISPLAY INVISIBLE (-4475 6200);
FORCEADD Q_CAP..1
(-8625 3000);
FORCEPROP 1 LAST LOCATION C2538
J 0
(-8575 3100);
DISPLAY 0.489362 (-8575 3100);
PAINT SKYBLUE (-8575 3100);
FORCEPROP 2 LAST $SEC 1
J 0
(-8575 3200);
DISPLAY 0.680851 (-8575 3200);
PAINT MONO (-8575 3200);
DISPLAY INVISIBLE (-8575 3200);
FORCEPROP 2 LAST CDS_SEC 1
J 0
(-8575 3200);
DISPLAY 1.021277 (-8575 3200);
DISPLAY INVISIBLE (-8575 3200);
FORCEPROP 1 LASTPIN (-8625 3100) $PN 1
J 0
(-8615 3080);
DISPLAY 0.489362 (-8615 3080);
FORCEPROP 1 LASTPIN (-8625 2900) $PN 2
J 0
(-8615 2880);
DISPLAY 0.489362 (-8615 2880);
FORCEPROP 1 LAST MATERIAL X6S
J 0
(-8575 2900);
DISPLAY 0.489362 (-8575 2900);
PAINT SKYBLUE (-8575 2900);
FORCEPROP 1 LAST TOLERANCE 20%
J 0
(-8575 2950);
DISPLAY 0.489362 (-8575 2950);
PAINT SKYBLUE (-8575 2950);
FORCEPROP 1 LAST VALUE 22UF
J 0
(-8575 3050);
DISPLAY 0.489362 (-8575 3050);
PAINT SKYBLUE (-8575 3050);
FORCEPROP 1 LAST VOLTAGE 4V
J 0
(-8575 3000);
DISPLAY 0.489362 (-8575 3000);
PAINT SKYBLUE (-8575 3000);
FORCEPROP 1 LAST PACK_TYPE C0402
J 0
(-8575 2800);
DISPLAY 0.489362 (-8575 2800);
PAINT SKYBLUE (-8575 2800);
FORCEPROP 2 LAST CDS_LIB pure_quanta
J 0
(-8625 3000);
PAINT MONO (-8625 3000);
DISPLAY INVISIBLE (-8625 3000);
FORCEPROP 1 LAST PATH I11
J 0
(-8575 3150);
DISPLAY 0.978723 (-8575 3150);
PAINT WHITE (-8575 3150);
DISPLAY INVISIBLE (-8575 3150);
FORCEPROP 1 LAST PART_NUMBER CH622KMEB02
J 0
(-8575 2850);
DISPLAY 0.489362 (-8575 2850);
PAINT SKYBLUE (-8575 2850);
DISPLAY INVISIBLE (-8575 2850);
FORCEADD UNIVERSAL_GND..1
(-4050 475);
FORCEPROP 3 LASTPIN (-4050 525) SIG_NAME GND\g
J 0
(-4040 535);
DISPLAY 0.659574 (-4040 535);
PAINT MONO (-4040 535);
DISPLAY INVISIBLE (-4040 535);
FORCEPROP 2 LAST CDS_LIB pure_quanta_power
J 0
(-4050 475);
DISPLAY INVISIBLE (-4050 475);
FORCEPROP 1 LAST HDL_POWER GND
J 1
(-4025 400);
DISPLAY 0.872340 (-4025 400);
PAINT GREEN (-4025 400);
DISPLAY INVISIBLE (-4025 400);
FORCEPROP 1 LAST PATH I110
J 0
(-3975 475);
DISPLAY 0.872340 (-3975 475);
PAINT AQUA (-3975 475);
DISPLAY INVISIBLE (-3975 475);
FORCEADD Q_CAP..1
(-4050 800);
FORCEPROP 1 LAST LOCATION C3933
J 0
(-4000 900);
DISPLAY 0.489362 (-4000 900);
PAINT SKYBLUE (-4000 900);
FORCEPROP 2 LAST $SEC 1
J 0
(-4000 1000);
DISPLAY 0.680851 (-4000 1000);
PAINT MONO (-4000 1000);
DISPLAY INVISIBLE (-4000 1000);
FORCEPROP 2 LAST CDS_SEC 1
J 0
(-4000 1000);
DISPLAY 1.021277 (-4000 1000);
DISPLAY INVISIBLE (-4000 1000);
FORCEPROP 1 LASTPIN (-4050 900) $PN 1
J 0
(-4040 880);
DISPLAY 0.489362 (-4040 880);
FORCEPROP 1 LASTPIN (-4050 700) $PN 2
J 0
(-4040 680);
DISPLAY 0.489362 (-4040 680);
FORCEPROP 1 LAST MATERIAL X6S
J 0
(-4000 700);
DISPLAY 0.489362 (-4000 700);
PAINT SKYBLUE (-4000 700);
FORCEPROP 1 LAST TOLERANCE 20%
J 0
(-4000 750);
DISPLAY 0.489362 (-4000 750);
PAINT SKYBLUE (-4000 750);
FORCEPROP 1 LAST VALUE 22UF
J 0
(-4000 850);
DISPLAY 0.489362 (-4000 850);
PAINT SKYBLUE (-4000 850);
FORCEPROP 1 LAST VOLTAGE 4V
J 0
(-4000 800);
DISPLAY 0.489362 (-4000 800);
PAINT SKYBLUE (-4000 800);
FORCEPROP 1 LAST PACK_TYPE C0402
J 0
(-4000 600);
DISPLAY 0.489362 (-4000 600);
PAINT SKYBLUE (-4000 600);
FORCEPROP 2 LAST CDS_LIB pure_quanta
J 0
(-4050 800);
PAINT MONO (-4050 800);
DISPLAY INVISIBLE (-4050 800);
FORCEPROP 1 LAST PATH I111
J 0
(-4000 950);
DISPLAY 0.978723 (-4000 950);
PAINT WHITE (-4000 950);
DISPLAY INVISIBLE (-4000 950);
FORCEPROP 1 LAST PART_NUMBER CH622KMEB02
J 0
(-4000 650);
DISPLAY 0.489362 (-4000 650);
PAINT SKYBLUE (-4000 650);
DISPLAY INVISIBLE (-4000 650);
FORCEADD Q_CAP..1
(-4050 1400);
FORCEPROP 1 LAST LOCATION C2610
J 0
(-4000 1500);
DISPLAY 0.489362 (-4000 1500);
PAINT SKYBLUE (-4000 1500);
FORCEPROP 2 LAST $SEC 1
J 0
(-4000 1600);
DISPLAY 0.680851 (-4000 1600);
PAINT MONO (-4000 1600);
DISPLAY INVISIBLE (-4000 1600);
FORCEPROP 2 LAST CDS_SEC 1
J 0
(-4000 1600);
DISPLAY 1.021277 (-4000 1600);
DISPLAY INVISIBLE (-4000 1600);
FORCEPROP 1 LASTPIN (-4050 1500) $PN 1
J 0
(-4040 1480);
DISPLAY 0.489362 (-4040 1480);
FORCEPROP 1 LASTPIN (-4050 1300) $PN 2
J 0
(-4040 1280);
DISPLAY 0.489362 (-4040 1280);
FORCEPROP 1 LAST MATERIAL X6S
J 0
(-4000 1300);
DISPLAY 0.489362 (-4000 1300);
PAINT SKYBLUE (-4000 1300);
FORCEPROP 1 LAST TOLERANCE 20%
J 0
(-4000 1350);
DISPLAY 0.489362 (-4000 1350);
PAINT SKYBLUE (-4000 1350);
FORCEPROP 1 LAST VALUE 22UF
J 0
(-4000 1450);
DISPLAY 0.489362 (-4000 1450);
PAINT SKYBLUE (-4000 1450);
FORCEPROP 1 LAST VOLTAGE 4V
J 0
(-4000 1400);
DISPLAY 0.489362 (-4000 1400);
PAINT SKYBLUE (-4000 1400);
FORCEPROP 1 LAST PACK_TYPE C0402
J 0
(-4000 1200);
DISPLAY 0.489362 (-4000 1200);
PAINT SKYBLUE (-4000 1200);
FORCEPROP 2 LAST CDS_LIB pure_quanta
J 0
(-4050 1400);
PAINT MONO (-4050 1400);
DISPLAY INVISIBLE (-4050 1400);
FORCEPROP 1 LAST PATH I112
J 0
(-4000 1550);
DISPLAY 0.978723 (-4000 1550);
PAINT WHITE (-4000 1550);
DISPLAY INVISIBLE (-4000 1550);
FORCEPROP 1 LAST PART_NUMBER CH622KMEB02
J 0
(-4000 1250);
DISPLAY 0.489362 (-4000 1250);
PAINT SKYBLUE (-4000 1250);
DISPLAY INVISIBLE (-4000 1250);
FORCEADD Q_CAP..1
(-4050 2000);
FORCEPROP 1 LAST LOCATION C2609
J 0
(-4000 2100);
DISPLAY 0.489362 (-4000 2100);
PAINT SKYBLUE (-4000 2100);
FORCEPROP 2 LAST $SEC 1
J 0
(-4000 2200);
DISPLAY 0.680851 (-4000 2200);
PAINT MONO (-4000 2200);
DISPLAY INVISIBLE (-4000 2200);
FORCEPROP 2 LAST CDS_SEC 1
J 0
(-4000 2200);
DISPLAY 1.021277 (-4000 2200);
DISPLAY INVISIBLE (-4000 2200);
FORCEPROP 1 LASTPIN (-4050 2100) $PN 1
J 0
(-4040 2080);
DISPLAY 0.489362 (-4040 2080);
FORCEPROP 1 LASTPIN (-4050 1900) $PN 2
J 0
(-4040 1880);
DISPLAY 0.489362 (-4040 1880);
FORCEPROP 1 LAST MATERIAL X6S
J 0
(-4000 1900);
DISPLAY 0.489362 (-4000 1900);
PAINT SKYBLUE (-4000 1900);
FORCEPROP 1 LAST TOLERANCE 20%
J 0
(-4000 1950);
DISPLAY 0.489362 (-4000 1950);
PAINT SKYBLUE (-4000 1950);
FORCEPROP 1 LAST VALUE 22UF
J 0
(-4000 2050);
DISPLAY 0.489362 (-4000 2050);
PAINT SKYBLUE (-4000 2050);
FORCEPROP 1 LAST VOLTAGE 4V
J 0
(-4000 2000);
DISPLAY 0.489362 (-4000 2000);
PAINT SKYBLUE (-4000 2000);
FORCEPROP 1 LAST PACK_TYPE C0402
J 0
(-4000 1800);
DISPLAY 0.489362 (-4000 1800);
PAINT SKYBLUE (-4000 1800);
FORCEPROP 2 LAST CDS_LIB pure_quanta
J 0
(-4050 2000);
PAINT MONO (-4050 2000);
DISPLAY INVISIBLE (-4050 2000);
FORCEPROP 1 LAST PATH I113
J 0
(-4000 2150);
DISPLAY 0.978723 (-4000 2150);
PAINT WHITE (-4000 2150);
DISPLAY INVISIBLE (-4000 2150);
FORCEPROP 1 LAST PART_NUMBER CH622KMEB02
J 0
(-4000 1850);
DISPLAY 0.489362 (-4000 1850);
PAINT SKYBLUE (-4000 1850);
DISPLAY INVISIBLE (-4000 1850);
FORCEADD Q_CAP..1
(-3600 1400);
FORCEPROP 1 LAST LOCATION C2617
J 0
(-3550 1500);
DISPLAY 0.489362 (-3550 1500);
PAINT SKYBLUE (-3550 1500);
FORCEPROP 2 LAST $SEC 1
J 0
(-3550 1600);
DISPLAY 0.680851 (-3550 1600);
PAINT MONO (-3550 1600);
DISPLAY INVISIBLE (-3550 1600);
FORCEPROP 2 LAST CDS_SEC 1
J 0
(-3550 1600);
DISPLAY 1.021277 (-3550 1600);
DISPLAY INVISIBLE (-3550 1600);
FORCEPROP 1 LASTPIN (-3600 1500) $PN 1
J 0
(-3590 1480);
DISPLAY 0.489362 (-3590 1480);
FORCEPROP 1 LASTPIN (-3600 1300) $PN 2
J 0
(-3590 1280);
DISPLAY 0.489362 (-3590 1280);
FORCEPROP 1 LAST MATERIAL X6S
J 0
(-3550 1300);
DISPLAY 0.489362 (-3550 1300);
PAINT SKYBLUE (-3550 1300);
FORCEPROP 1 LAST TOLERANCE 20%
J 0
(-3550 1350);
DISPLAY 0.489362 (-3550 1350);
PAINT SKYBLUE (-3550 1350);
FORCEPROP 1 LAST VALUE 22UF
J 0
(-3550 1450);
DISPLAY 0.489362 (-3550 1450);
PAINT SKYBLUE (-3550 1450);
FORCEPROP 1 LAST VOLTAGE 4V
J 0
(-3550 1400);
DISPLAY 0.489362 (-3550 1400);
PAINT SKYBLUE (-3550 1400);
FORCEPROP 1 LAST PACK_TYPE C0402
J 0
(-3550 1200);
DISPLAY 0.489362 (-3550 1200);
PAINT SKYBLUE (-3550 1200);
FORCEPROP 2 LAST CDS_LIB pure_quanta
J 0
(-3600 1400);
PAINT MONO (-3600 1400);
DISPLAY INVISIBLE (-3600 1400);
FORCEPROP 1 LAST PATH I114
J 0
(-3550 1550);
DISPLAY 0.978723 (-3550 1550);
PAINT WHITE (-3550 1550);
DISPLAY INVISIBLE (-3550 1550);
FORCEPROP 1 LAST PART_NUMBER CH622KMEB02
J 0
(-3550 1250);
DISPLAY 0.489362 (-3550 1250);
PAINT SKYBLUE (-3550 1250);
DISPLAY INVISIBLE (-3550 1250);
FORCEADD Q_CAP..1
(-3600 2000);
FORCEPROP 1 LAST LOCATION C2616
J 0
(-3550 2100);
DISPLAY 0.489362 (-3550 2100);
PAINT SKYBLUE (-3550 2100);
FORCEPROP 2 LAST $SEC 1
J 0
(-3550 2200);
DISPLAY 0.680851 (-3550 2200);
PAINT MONO (-3550 2200);
DISPLAY INVISIBLE (-3550 2200);
FORCEPROP 2 LAST CDS_SEC 1
J 0
(-3550 2200);
DISPLAY 1.021277 (-3550 2200);
DISPLAY INVISIBLE (-3550 2200);
FORCEPROP 1 LASTPIN (-3600 2100) $PN 1
J 0
(-3590 2080);
DISPLAY 0.489362 (-3590 2080);
FORCEPROP 1 LASTPIN (-3600 1900) $PN 2
J 0
(-3590 1880);
DISPLAY 0.489362 (-3590 1880);
FORCEPROP 1 LAST MATERIAL X6S
J 0
(-3550 1900);
DISPLAY 0.489362 (-3550 1900);
PAINT SKYBLUE (-3550 1900);
FORCEPROP 1 LAST TOLERANCE 20%
J 0
(-3550 1950);
DISPLAY 0.489362 (-3550 1950);
PAINT SKYBLUE (-3550 1950);
FORCEPROP 1 LAST VALUE 22UF
J 0
(-3550 2050);
DISPLAY 0.489362 (-3550 2050);
PAINT SKYBLUE (-3550 2050);
FORCEPROP 1 LAST VOLTAGE 4V
J 0
(-3550 2000);
DISPLAY 0.489362 (-3550 2000);
PAINT SKYBLUE (-3550 2000);
FORCEPROP 1 LAST PACK_TYPE C0402
J 0
(-3550 1800);
DISPLAY 0.489362 (-3550 1800);
PAINT SKYBLUE (-3550 1800);
FORCEPROP 2 LAST CDS_LIB pure_quanta
J 0
(-3600 2000);
PAINT MONO (-3600 2000);
DISPLAY INVISIBLE (-3600 2000);
FORCEPROP 1 LAST PATH I115
J 0
(-3550 2150);
DISPLAY 0.978723 (-3550 2150);
PAINT WHITE (-3550 2150);
DISPLAY INVISIBLE (-3550 2150);
FORCEPROP 1 LAST PART_NUMBER CH622KMEB02
J 0
(-3550 1850);
DISPLAY 0.489362 (-3550 1850);
PAINT SKYBLUE (-3550 1850);
DISPLAY INVISIBLE (-3550 1850);
FORCEADD Q_CAP..1
(-3150 1400);
FORCEPROP 1 LAST LOCATION C2624
J 0
(-3100 1500);
DISPLAY 0.489362 (-3100 1500);
PAINT SKYBLUE (-3100 1500);
FORCEPROP 2 LAST $SEC 1
J 0
(-3100 1600);
DISPLAY 0.680851 (-3100 1600);
PAINT MONO (-3100 1600);
DISPLAY INVISIBLE (-3100 1600);
FORCEPROP 2 LAST CDS_SEC 1
J 0
(-3100 1600);
DISPLAY 1.021277 (-3100 1600);
DISPLAY INVISIBLE (-3100 1600);
FORCEPROP 1 LASTPIN (-3150 1500) $PN 1
J 0
(-3140 1480);
DISPLAY 0.489362 (-3140 1480);
FORCEPROP 1 LASTPIN (-3150 1300) $PN 2
J 0
(-3140 1280);
DISPLAY 0.489362 (-3140 1280);
FORCEPROP 1 LAST MATERIAL X6S
J 0
(-3100 1300);
DISPLAY 0.489362 (-3100 1300);
PAINT SKYBLUE (-3100 1300);
FORCEPROP 1 LAST TOLERANCE 20%
J 0
(-3100 1350);
DISPLAY 0.489362 (-3100 1350);
PAINT SKYBLUE (-3100 1350);
FORCEPROP 1 LAST VALUE 22UF
J 0
(-3100 1450);
DISPLAY 0.489362 (-3100 1450);
PAINT SKYBLUE (-3100 1450);
FORCEPROP 1 LAST VOLTAGE 4V
J 0
(-3100 1400);
DISPLAY 0.489362 (-3100 1400);
PAINT SKYBLUE (-3100 1400);
FORCEPROP 1 LAST PACK_TYPE C0402
J 0
(-3100 1200);
DISPLAY 0.489362 (-3100 1200);
PAINT SKYBLUE (-3100 1200);
FORCEPROP 2 LAST CDS_LIB pure_quanta
J 0
(-3150 1400);
PAINT MONO (-3150 1400);
DISPLAY INVISIBLE (-3150 1400);
FORCEPROP 1 LAST PATH I116
J 0
(-3100 1550);
DISPLAY 0.978723 (-3100 1550);
PAINT WHITE (-3100 1550);
DISPLAY INVISIBLE (-3100 1550);
FORCEPROP 1 LAST PART_NUMBER CH622KMEB02
J 0
(-3100 1250);
DISPLAY 0.489362 (-3100 1250);
PAINT SKYBLUE (-3100 1250);
DISPLAY INVISIBLE (-3100 1250);
FORCEADD Q_CAP..1
(-3150 2000);
FORCEPROP 1 LAST LOCATION C2623
J 0
(-3100 2100);
DISPLAY 0.489362 (-3100 2100);
PAINT SKYBLUE (-3100 2100);
FORCEPROP 2 LAST $SEC 1
J 0
(-3100 2200);
DISPLAY 0.680851 (-3100 2200);
PAINT MONO (-3100 2200);
DISPLAY INVISIBLE (-3100 2200);
FORCEPROP 2 LAST CDS_SEC 1
J 0
(-3100 2200);
DISPLAY 1.021277 (-3100 2200);
DISPLAY INVISIBLE (-3100 2200);
FORCEPROP 1 LASTPIN (-3150 2100) $PN 1
J 0
(-3140 2080);
DISPLAY 0.489362 (-3140 2080);
FORCEPROP 1 LASTPIN (-3150 1900) $PN 2
J 0
(-3140 1880);
DISPLAY 0.489362 (-3140 1880);
FORCEPROP 1 LAST MATERIAL X6S
J 0
(-3100 1900);
DISPLAY 0.489362 (-3100 1900);
PAINT SKYBLUE (-3100 1900);
FORCEPROP 1 LAST TOLERANCE 20%
J 0
(-3100 1950);
DISPLAY 0.489362 (-3100 1950);
PAINT SKYBLUE (-3100 1950);
FORCEPROP 1 LAST VALUE 22UF
J 0
(-3100 2050);
DISPLAY 0.489362 (-3100 2050);
PAINT SKYBLUE (-3100 2050);
FORCEPROP 1 LAST VOLTAGE 4V
J 0
(-3100 2000);
DISPLAY 0.489362 (-3100 2000);
PAINT SKYBLUE (-3100 2000);
FORCEPROP 1 LAST PACK_TYPE C0402
J 0
(-3100 1800);
DISPLAY 0.489362 (-3100 1800);
PAINT SKYBLUE (-3100 1800);
FORCEPROP 2 LAST CDS_LIB pure_quanta
J 0
(-3150 2000);
PAINT MONO (-3150 2000);
DISPLAY INVISIBLE (-3150 2000);
FORCEPROP 1 LAST PATH I117
J 0
(-3100 2150);
DISPLAY 0.978723 (-3100 2150);
PAINT WHITE (-3100 2150);
DISPLAY INVISIBLE (-3100 2150);
FORCEPROP 1 LAST PART_NUMBER CH622KMEB02
J 0
(-3100 1850);
DISPLAY 0.489362 (-3100 1850);
PAINT SKYBLUE (-3100 1850);
DISPLAY INVISIBLE (-3100 1850);
FORCEADD Q_CAP..1
(-2700 1400);
FORCEPROP 1 LAST LOCATION C2630
J 0
(-2650 1500);
DISPLAY 0.489362 (-2650 1500);
PAINT SKYBLUE (-2650 1500);
FORCEPROP 2 LAST $SEC 1
J 0
(-2650 1600);
DISPLAY 0.680851 (-2650 1600);
PAINT MONO (-2650 1600);
DISPLAY INVISIBLE (-2650 1600);
FORCEPROP 2 LAST CDS_SEC 1
J 0
(-2650 1600);
DISPLAY 1.021277 (-2650 1600);
DISPLAY INVISIBLE (-2650 1600);
FORCEPROP 1 LASTPIN (-2700 1500) $PN 1
J 0
(-2690 1480);
DISPLAY 0.489362 (-2690 1480);
FORCEPROP 1 LASTPIN (-2700 1300) $PN 2
J 0
(-2690 1280);
DISPLAY 0.489362 (-2690 1280);
FORCEPROP 1 LAST MATERIAL X6S
J 0
(-2650 1300);
DISPLAY 0.489362 (-2650 1300);
PAINT SKYBLUE (-2650 1300);
FORCEPROP 1 LAST TOLERANCE 20%
J 0
(-2650 1350);
DISPLAY 0.489362 (-2650 1350);
PAINT SKYBLUE (-2650 1350);
FORCEPROP 1 LAST VALUE 22UF
J 0
(-2650 1450);
DISPLAY 0.489362 (-2650 1450);
PAINT SKYBLUE (-2650 1450);
FORCEPROP 1 LAST VOLTAGE 4V
J 0
(-2650 1400);
DISPLAY 0.489362 (-2650 1400);
PAINT SKYBLUE (-2650 1400);
FORCEPROP 1 LAST PACK_TYPE C0402
J 0
(-2650 1200);
DISPLAY 0.489362 (-2650 1200);
PAINT SKYBLUE (-2650 1200);
FORCEPROP 2 LAST CDS_LIB pure_quanta
J 0
(-2700 1400);
PAINT MONO (-2700 1400);
DISPLAY INVISIBLE (-2700 1400);
FORCEPROP 1 LAST PATH I118
J 0
(-2650 1550);
DISPLAY 0.978723 (-2650 1550);
PAINT WHITE (-2650 1550);
DISPLAY INVISIBLE (-2650 1550);
FORCEPROP 1 LAST PART_NUMBER CH622KMEB02
J 0
(-2650 1250);
DISPLAY 0.489362 (-2650 1250);
PAINT SKYBLUE (-2650 1250);
DISPLAY INVISIBLE (-2650 1250);
FORCEADD Q_CAP..1
(-2700 2000);
FORCEPROP 1 LAST LOCATION C2629
J 0
(-2650 2100);
DISPLAY 0.489362 (-2650 2100);
PAINT SKYBLUE (-2650 2100);
FORCEPROP 2 LAST $SEC 1
J 0
(-2650 2200);
DISPLAY 0.680851 (-2650 2200);
PAINT MONO (-2650 2200);
DISPLAY INVISIBLE (-2650 2200);
FORCEPROP 2 LAST CDS_SEC 1
J 0
(-2650 2200);
DISPLAY 1.021277 (-2650 2200);
DISPLAY INVISIBLE (-2650 2200);
FORCEPROP 1 LASTPIN (-2700 2100) $PN 1
J 0
(-2690 2080);
DISPLAY 0.489362 (-2690 2080);
FORCEPROP 1 LASTPIN (-2700 1900) $PN 2
J 0
(-2690 1880);
DISPLAY 0.489362 (-2690 1880);
FORCEPROP 1 LAST MATERIAL X6S
J 0
(-2650 1900);
DISPLAY 0.489362 (-2650 1900);
PAINT SKYBLUE (-2650 1900);
FORCEPROP 1 LAST TOLERANCE 20%
J 0
(-2650 1950);
DISPLAY 0.489362 (-2650 1950);
PAINT SKYBLUE (-2650 1950);
FORCEPROP 1 LAST VALUE 22UF
J 0
(-2650 2050);
DISPLAY 0.489362 (-2650 2050);
PAINT SKYBLUE (-2650 2050);
FORCEPROP 1 LAST VOLTAGE 4V
J 0
(-2650 2000);
DISPLAY 0.489362 (-2650 2000);
PAINT SKYBLUE (-2650 2000);
FORCEPROP 1 LAST PACK_TYPE C0402
J 0
(-2650 1800);
DISPLAY 0.489362 (-2650 1800);
PAINT SKYBLUE (-2650 1800);
FORCEPROP 2 LAST CDS_LIB pure_quanta
J 0
(-2700 2000);
PAINT MONO (-2700 2000);
DISPLAY INVISIBLE (-2700 2000);
FORCEPROP 1 LAST PATH I119
J 0
(-2650 2150);
DISPLAY 0.978723 (-2650 2150);
PAINT WHITE (-2650 2150);
DISPLAY INVISIBLE (-2650 2150);
FORCEPROP 1 LAST PART_NUMBER CH622KMEB02
J 0
(-2650 1850);
DISPLAY 0.489362 (-2650 1850);
PAINT SKYBLUE (-2650 1850);
DISPLAY INVISIBLE (-2650 1850);
FORCEADD UNIVERSAL_POWER..1
(-9075 3275);
FORCEPROP 3 LASTPIN (-9075 3225) SIG_NAME PVDDCR_SOC_P0\g
J 0
(-9065 3235);
DISPLAY 0.659574 (-9065 3235);
PAINT MONO (-9065 3235);
DISPLAY INVISIBLE (-9065 3235);
FORCEPROP 1 LAST HDL_POWER PVDDCR_SOC_P0
J 1
(-9075 3325);
DISPLAY 0.489362 (-9075 3325);
PAINT GREEN (-9075 3325);
FORCEPROP 2 LAST CDS_LIB pure_quanta_power
J 0
(-9075 3275);
DISPLAY INVISIBLE (-9075 3275);
FORCEPROP 1 LAST PATH I12
J 0
(-9025 3300);
DISPLAY 0.872340 (-9025 3300);
PAINT AQUA (-9025 3300);
DISPLAY INVISIBLE (-9025 3300);
FORCEADD Q_CAP..1
(-2250 1400);
FORCEPROP 1 LAST LOCATION C2636
J 0
(-2200 1500);
DISPLAY 0.489362 (-2200 1500);
PAINT SKYBLUE (-2200 1500);
FORCEPROP 2 LAST $SEC 1
J 0
(-2200 1600);
DISPLAY 0.680851 (-2200 1600);
PAINT MONO (-2200 1600);
DISPLAY INVISIBLE (-2200 1600);
FORCEPROP 2 LAST CDS_SEC 1
J 0
(-2200 1600);
DISPLAY 1.021277 (-2200 1600);
DISPLAY INVISIBLE (-2200 1600);
FORCEPROP 1 LASTPIN (-2250 1500) $PN 1
J 0
(-2240 1480);
DISPLAY 0.489362 (-2240 1480);
FORCEPROP 1 LASTPIN (-2250 1300) $PN 2
J 0
(-2240 1280);
DISPLAY 0.489362 (-2240 1280);
FORCEPROP 1 LAST MATERIAL X6S
J 0
(-2200 1300);
DISPLAY 0.489362 (-2200 1300);
PAINT SKYBLUE (-2200 1300);
FORCEPROP 1 LAST TOLERANCE 20%
J 0
(-2200 1350);
DISPLAY 0.489362 (-2200 1350);
PAINT SKYBLUE (-2200 1350);
FORCEPROP 1 LAST VALUE 22UF
J 0
(-2200 1450);
DISPLAY 0.489362 (-2200 1450);
PAINT SKYBLUE (-2200 1450);
FORCEPROP 1 LAST VOLTAGE 4V
J 0
(-2200 1400);
DISPLAY 0.489362 (-2200 1400);
PAINT SKYBLUE (-2200 1400);
FORCEPROP 1 LAST PACK_TYPE C0402
J 0
(-2200 1200);
DISPLAY 0.489362 (-2200 1200);
PAINT SKYBLUE (-2200 1200);
FORCEPROP 2 LAST CDS_LIB pure_quanta
J 0
(-2250 1400);
PAINT MONO (-2250 1400);
DISPLAY INVISIBLE (-2250 1400);
FORCEPROP 1 LAST PATH I120
J 0
(-2200 1550);
DISPLAY 0.978723 (-2200 1550);
PAINT WHITE (-2200 1550);
DISPLAY INVISIBLE (-2200 1550);
FORCEPROP 1 LAST PART_NUMBER CH622KMEB02
J 0
(-2200 1250);
DISPLAY 0.489362 (-2200 1250);
PAINT SKYBLUE (-2200 1250);
DISPLAY INVISIBLE (-2200 1250);
FORCEADD Q_CAP..1
(-2250 2000);
FORCEPROP 1 LAST LOCATION C2635
J 0
(-2200 2100);
DISPLAY 0.489362 (-2200 2100);
PAINT SKYBLUE (-2200 2100);
FORCEPROP 2 LAST $SEC 1
J 0
(-2200 2200);
DISPLAY 0.680851 (-2200 2200);
PAINT MONO (-2200 2200);
DISPLAY INVISIBLE (-2200 2200);
FORCEPROP 2 LAST CDS_SEC 1
J 0
(-2200 2200);
DISPLAY 1.021277 (-2200 2200);
DISPLAY INVISIBLE (-2200 2200);
FORCEPROP 1 LASTPIN (-2250 2100) $PN 1
J 0
(-2240 2080);
DISPLAY 0.489362 (-2240 2080);
FORCEPROP 1 LASTPIN (-2250 1900) $PN 2
J 0
(-2240 1880);
DISPLAY 0.489362 (-2240 1880);
FORCEPROP 1 LAST MATERIAL X6S
J 0
(-2200 1900);
DISPLAY 0.489362 (-2200 1900);
PAINT SKYBLUE (-2200 1900);
FORCEPROP 1 LAST TOLERANCE 20%
J 0
(-2200 1950);
DISPLAY 0.489362 (-2200 1950);
PAINT SKYBLUE (-2200 1950);
FORCEPROP 1 LAST VALUE 22UF
J 0
(-2200 2050);
DISPLAY 0.489362 (-2200 2050);
PAINT SKYBLUE (-2200 2050);
FORCEPROP 1 LAST VOLTAGE 4V
J 0
(-2200 2000);
DISPLAY 0.489362 (-2200 2000);
PAINT SKYBLUE (-2200 2000);
FORCEPROP 1 LAST PACK_TYPE C0402
J 0
(-2200 1800);
DISPLAY 0.489362 (-2200 1800);
PAINT SKYBLUE (-2200 1800);
FORCEPROP 2 LAST CDS_LIB pure_quanta
J 0
(-2250 2000);
PAINT MONO (-2250 2000);
DISPLAY INVISIBLE (-2250 2000);
FORCEPROP 1 LAST PATH I121
J 0
(-2200 2150);
DISPLAY 0.978723 (-2200 2150);
PAINT WHITE (-2200 2150);
DISPLAY INVISIBLE (-2200 2150);
FORCEPROP 1 LAST PART_NUMBER CH622KMEB02
J 0
(-2200 1850);
DISPLAY 0.489362 (-2200 1850);
PAINT SKYBLUE (-2200 1850);
DISPLAY INVISIBLE (-2200 1850);
FORCEADD Q_CAP..1
(-4050 2625);
FORCEPROP 1 LAST LOCATION C2608
J 0
(-4000 2725);
DISPLAY 0.489362 (-4000 2725);
PAINT SKYBLUE (-4000 2725);
FORCEPROP 2 LAST $SEC 1
J 0
(-4000 2825);
DISPLAY 0.680851 (-4000 2825);
PAINT MONO (-4000 2825);
DISPLAY INVISIBLE (-4000 2825);
FORCEPROP 2 LAST CDS_SEC 1
J 0
(-4000 2825);
DISPLAY 1.021277 (-4000 2825);
DISPLAY INVISIBLE (-4000 2825);
FORCEPROP 1 LASTPIN (-4050 2725) $PN 1
J 0
(-4040 2705);
DISPLAY 0.489362 (-4040 2705);
FORCEPROP 1 LASTPIN (-4050 2525) $PN 2
J 0
(-4040 2505);
DISPLAY 0.489362 (-4040 2505);
FORCEPROP 1 LAST MATERIAL X6S
J 0
(-4000 2525);
DISPLAY 0.489362 (-4000 2525);
PAINT SKYBLUE (-4000 2525);
FORCEPROP 1 LAST TOLERANCE 20%
J 0
(-4000 2575);
DISPLAY 0.489362 (-4000 2575);
PAINT SKYBLUE (-4000 2575);
FORCEPROP 1 LAST VALUE 22UF
J 0
(-4000 2675);
DISPLAY 0.489362 (-4000 2675);
PAINT SKYBLUE (-4000 2675);
FORCEPROP 1 LAST VOLTAGE 4V
J 0
(-4000 2625);
DISPLAY 0.489362 (-4000 2625);
PAINT SKYBLUE (-4000 2625);
FORCEPROP 1 LAST PACK_TYPE C0402
J 0
(-4000 2425);
DISPLAY 0.489362 (-4000 2425);
PAINT SKYBLUE (-4000 2425);
FORCEPROP 2 LAST CDS_LIB pure_quanta
J 0
(-4050 2625);
PAINT MONO (-4050 2625);
DISPLAY INVISIBLE (-4050 2625);
FORCEPROP 1 LAST PATH I122
J 0
(-4000 2775);
DISPLAY 0.978723 (-4000 2775);
PAINT WHITE (-4000 2775);
DISPLAY INVISIBLE (-4000 2775);
FORCEPROP 1 LAST PART_NUMBER CH622KMEB02
J 0
(-4000 2475);
DISPLAY 0.489362 (-4000 2475);
PAINT SKYBLUE (-4000 2475);
DISPLAY INVISIBLE (-4000 2475);
FORCEADD Q_CAP..1
(-3600 2625);
FORCEPROP 1 LAST LOCATION C2615
J 0
(-3550 2725);
DISPLAY 0.489362 (-3550 2725);
PAINT SKYBLUE (-3550 2725);
FORCEPROP 2 LAST $SEC 1
J 0
(-3550 2825);
DISPLAY 0.680851 (-3550 2825);
PAINT MONO (-3550 2825);
DISPLAY INVISIBLE (-3550 2825);
FORCEPROP 2 LAST CDS_SEC 1
J 0
(-3550 2825);
DISPLAY 1.021277 (-3550 2825);
DISPLAY INVISIBLE (-3550 2825);
FORCEPROP 1 LASTPIN (-3600 2725) $PN 1
J 0
(-3590 2705);
DISPLAY 0.489362 (-3590 2705);
FORCEPROP 1 LASTPIN (-3600 2525) $PN 2
J 0
(-3590 2505);
DISPLAY 0.489362 (-3590 2505);
FORCEPROP 1 LAST MATERIAL X6S
J 0
(-3550 2525);
DISPLAY 0.489362 (-3550 2525);
PAINT SKYBLUE (-3550 2525);
FORCEPROP 1 LAST TOLERANCE 20%
J 0
(-3550 2575);
DISPLAY 0.489362 (-3550 2575);
PAINT SKYBLUE (-3550 2575);
FORCEPROP 1 LAST VALUE 22UF
J 0
(-3550 2675);
DISPLAY 0.489362 (-3550 2675);
PAINT SKYBLUE (-3550 2675);
FORCEPROP 1 LAST VOLTAGE 4V
J 0
(-3550 2625);
DISPLAY 0.489362 (-3550 2625);
PAINT SKYBLUE (-3550 2625);
FORCEPROP 1 LAST PACK_TYPE C0402
J 0
(-3550 2425);
DISPLAY 0.489362 (-3550 2425);
PAINT SKYBLUE (-3550 2425);
FORCEPROP 2 LAST CDS_LIB pure_quanta
J 0
(-3600 2625);
PAINT MONO (-3600 2625);
DISPLAY INVISIBLE (-3600 2625);
FORCEPROP 1 LAST PATH I123
J 0
(-3550 2775);
DISPLAY 0.978723 (-3550 2775);
PAINT WHITE (-3550 2775);
DISPLAY INVISIBLE (-3550 2775);
FORCEPROP 1 LAST PART_NUMBER CH622KMEB02
J 0
(-3550 2475);
DISPLAY 0.489362 (-3550 2475);
PAINT SKYBLUE (-3550 2475);
DISPLAY INVISIBLE (-3550 2475);
FORCEADD Q_CAP..1
(-4050 3275);
FORCEPROP 1 LAST LOCATION C2607
J 0
(-4000 3375);
DISPLAY 0.489362 (-4000 3375);
PAINT SKYBLUE (-4000 3375);
FORCEPROP 2 LAST $SEC 1
J 0
(-4000 3475);
DISPLAY 0.680851 (-4000 3475);
PAINT MONO (-4000 3475);
DISPLAY INVISIBLE (-4000 3475);
FORCEPROP 2 LAST CDS_SEC 1
J 0
(-4000 3475);
DISPLAY 1.021277 (-4000 3475);
DISPLAY INVISIBLE (-4000 3475);
FORCEPROP 1 LASTPIN (-4050 3375) $PN 1
J 0
(-4040 3355);
DISPLAY 0.489362 (-4040 3355);
FORCEPROP 1 LASTPIN (-4050 3175) $PN 2
J 0
(-4040 3155);
DISPLAY 0.489362 (-4040 3155);
FORCEPROP 1 LAST MATERIAL X6S
J 0
(-4000 3175);
DISPLAY 0.489362 (-4000 3175);
PAINT SKYBLUE (-4000 3175);
FORCEPROP 1 LAST TOLERANCE 20%
J 0
(-4000 3225);
DISPLAY 0.489362 (-4000 3225);
PAINT SKYBLUE (-4000 3225);
FORCEPROP 1 LAST VALUE 22UF
J 0
(-4000 3325);
DISPLAY 0.489362 (-4000 3325);
PAINT SKYBLUE (-4000 3325);
FORCEPROP 1 LAST VOLTAGE 4V
J 0
(-4000 3275);
DISPLAY 0.489362 (-4000 3275);
PAINT SKYBLUE (-4000 3275);
FORCEPROP 1 LAST PACK_TYPE C0402
J 0
(-4000 3075);
DISPLAY 0.489362 (-4000 3075);
PAINT SKYBLUE (-4000 3075);
FORCEPROP 2 LAST CDS_LIB pure_quanta
J 0
(-4050 3275);
PAINT MONO (-4050 3275);
DISPLAY INVISIBLE (-4050 3275);
FORCEPROP 1 LAST PATH I124
J 0
(-4000 3425);
DISPLAY 0.978723 (-4000 3425);
PAINT WHITE (-4000 3425);
DISPLAY INVISIBLE (-4000 3425);
FORCEPROP 1 LAST PART_NUMBER CH622KMEB02
J 0
(-4000 3125);
DISPLAY 0.489362 (-4000 3125);
PAINT SKYBLUE (-4000 3125);
DISPLAY INVISIBLE (-4000 3125);
FORCEADD Q_CAP..1
(-3600 3275);
FORCEPROP 1 LAST LOCATION C2614
J 0
(-3550 3375);
DISPLAY 0.489362 (-3550 3375);
PAINT SKYBLUE (-3550 3375);
FORCEPROP 2 LAST $SEC 1
J 0
(-3550 3475);
DISPLAY 0.680851 (-3550 3475);
PAINT MONO (-3550 3475);
DISPLAY INVISIBLE (-3550 3475);
FORCEPROP 2 LAST CDS_SEC 1
J 0
(-3550 3475);
DISPLAY 1.021277 (-3550 3475);
DISPLAY INVISIBLE (-3550 3475);
FORCEPROP 1 LASTPIN (-3600 3375) $PN 1
J 0
(-3590 3355);
DISPLAY 0.489362 (-3590 3355);
FORCEPROP 1 LASTPIN (-3600 3175) $PN 2
J 0
(-3590 3155);
DISPLAY 0.489362 (-3590 3155);
FORCEPROP 1 LAST MATERIAL X6S
J 0
(-3550 3175);
DISPLAY 0.489362 (-3550 3175);
PAINT SKYBLUE (-3550 3175);
FORCEPROP 1 LAST TOLERANCE 20%
J 0
(-3550 3225);
DISPLAY 0.489362 (-3550 3225);
PAINT SKYBLUE (-3550 3225);
FORCEPROP 1 LAST VALUE 22UF
J 0
(-3550 3325);
DISPLAY 0.489362 (-3550 3325);
PAINT SKYBLUE (-3550 3325);
FORCEPROP 1 LAST VOLTAGE 4V
J 0
(-3550 3275);
DISPLAY 0.489362 (-3550 3275);
PAINT SKYBLUE (-3550 3275);
FORCEPROP 1 LAST PACK_TYPE C0402
J 0
(-3550 3075);
DISPLAY 0.489362 (-3550 3075);
PAINT SKYBLUE (-3550 3075);
FORCEPROP 2 LAST CDS_LIB pure_quanta
J 0
(-3600 3275);
PAINT MONO (-3600 3275);
DISPLAY INVISIBLE (-3600 3275);
FORCEPROP 1 LAST PATH I125
J 0
(-3550 3425);
DISPLAY 0.978723 (-3550 3425);
PAINT WHITE (-3550 3425);
DISPLAY INVISIBLE (-3550 3425);
FORCEPROP 1 LAST PART_NUMBER CH622KMEB02
J 0
(-3550 3125);
DISPLAY 0.489362 (-3550 3125);
PAINT SKYBLUE (-3550 3125);
DISPLAY INVISIBLE (-3550 3125);
FORCEADD Q_CAP..1
(-3150 2625);
FORCEPROP 1 LAST LOCATION C2622
J 0
(-3100 2725);
DISPLAY 0.489362 (-3100 2725);
PAINT SKYBLUE (-3100 2725);
FORCEPROP 2 LAST $SEC 1
J 0
(-3100 2825);
DISPLAY 0.680851 (-3100 2825);
PAINT MONO (-3100 2825);
DISPLAY INVISIBLE (-3100 2825);
FORCEPROP 2 LAST CDS_SEC 1
J 0
(-3100 2825);
DISPLAY 1.021277 (-3100 2825);
DISPLAY INVISIBLE (-3100 2825);
FORCEPROP 1 LASTPIN (-3150 2725) $PN 1
J 0
(-3140 2705);
DISPLAY 0.489362 (-3140 2705);
FORCEPROP 1 LASTPIN (-3150 2525) $PN 2
J 0
(-3140 2505);
DISPLAY 0.489362 (-3140 2505);
FORCEPROP 1 LAST MATERIAL X6S
J 0
(-3100 2525);
DISPLAY 0.489362 (-3100 2525);
PAINT SKYBLUE (-3100 2525);
FORCEPROP 1 LAST TOLERANCE 20%
J 0
(-3100 2575);
DISPLAY 0.489362 (-3100 2575);
PAINT SKYBLUE (-3100 2575);
FORCEPROP 1 LAST VALUE 22UF
J 0
(-3100 2675);
DISPLAY 0.489362 (-3100 2675);
PAINT SKYBLUE (-3100 2675);
FORCEPROP 1 LAST VOLTAGE 4V
J 0
(-3100 2625);
DISPLAY 0.489362 (-3100 2625);
PAINT SKYBLUE (-3100 2625);
FORCEPROP 1 LAST PACK_TYPE C0402
J 0
(-3100 2425);
DISPLAY 0.489362 (-3100 2425);
PAINT SKYBLUE (-3100 2425);
FORCEPROP 2 LAST CDS_LIB pure_quanta
J 0
(-3150 2625);
PAINT MONO (-3150 2625);
DISPLAY INVISIBLE (-3150 2625);
FORCEPROP 1 LAST PATH I126
J 0
(-3100 2775);
DISPLAY 0.978723 (-3100 2775);
PAINT WHITE (-3100 2775);
DISPLAY INVISIBLE (-3100 2775);
FORCEPROP 1 LAST PART_NUMBER CH622KMEB02
J 0
(-3100 2475);
DISPLAY 0.489362 (-3100 2475);
PAINT SKYBLUE (-3100 2475);
DISPLAY INVISIBLE (-3100 2475);
FORCEADD Q_CAP..1
(-3150 3275);
FORCEPROP 1 LAST LOCATION C2621
J 0
(-3100 3375);
DISPLAY 0.489362 (-3100 3375);
PAINT SKYBLUE (-3100 3375);
FORCEPROP 2 LAST $SEC 1
J 0
(-3100 3475);
DISPLAY 0.680851 (-3100 3475);
PAINT MONO (-3100 3475);
DISPLAY INVISIBLE (-3100 3475);
FORCEPROP 2 LAST CDS_SEC 1
J 0
(-3100 3475);
DISPLAY 1.021277 (-3100 3475);
DISPLAY INVISIBLE (-3100 3475);
FORCEPROP 1 LASTPIN (-3150 3375) $PN 1
J 0
(-3140 3355);
DISPLAY 0.489362 (-3140 3355);
FORCEPROP 1 LASTPIN (-3150 3175) $PN 2
J 0
(-3140 3155);
DISPLAY 0.489362 (-3140 3155);
FORCEPROP 1 LAST MATERIAL X6S
J 0
(-3100 3175);
DISPLAY 0.489362 (-3100 3175);
PAINT SKYBLUE (-3100 3175);
FORCEPROP 1 LAST TOLERANCE 20%
J 0
(-3100 3225);
DISPLAY 0.489362 (-3100 3225);
PAINT SKYBLUE (-3100 3225);
FORCEPROP 1 LAST VALUE 22UF
J 0
(-3100 3325);
DISPLAY 0.489362 (-3100 3325);
PAINT SKYBLUE (-3100 3325);
FORCEPROP 1 LAST VOLTAGE 4V
J 0
(-3100 3275);
DISPLAY 0.489362 (-3100 3275);
PAINT SKYBLUE (-3100 3275);
FORCEPROP 1 LAST PACK_TYPE C0402
J 0
(-3100 3075);
DISPLAY 0.489362 (-3100 3075);
PAINT SKYBLUE (-3100 3075);
FORCEPROP 2 LAST CDS_LIB pure_quanta
J 0
(-3150 3275);
PAINT MONO (-3150 3275);
DISPLAY INVISIBLE (-3150 3275);
FORCEPROP 1 LAST PATH I127
J 0
(-3100 3425);
DISPLAY 0.978723 (-3100 3425);
PAINT WHITE (-3100 3425);
DISPLAY INVISIBLE (-3100 3425);
FORCEPROP 1 LAST PART_NUMBER CH622KMEB02
J 0
(-3100 3125);
DISPLAY 0.489362 (-3100 3125);
PAINT SKYBLUE (-3100 3125);
DISPLAY INVISIBLE (-3100 3125);
FORCEADD UNIVERSAL_GND..1
(-3150 3950);
FORCEPROP 3 LASTPIN (-3150 4000) SIG_NAME GND\g
J 0
(-3140 4010);
DISPLAY 0.659574 (-3140 4010);
PAINT MONO (-3140 4010);
DISPLAY INVISIBLE (-3140 4010);
FORCEPROP 2 LAST CDS_LIB pure_quanta_power
J 0
(-3150 3950);
DISPLAY INVISIBLE (-3150 3950);
FORCEPROP 1 LAST HDL_POWER GND
J 1
(-3125 3875);
DISPLAY 0.872340 (-3125 3875);
PAINT GREEN (-3125 3875);
DISPLAY INVISIBLE (-3125 3875);
FORCEPROP 1 LAST PATH I128
J 0
(-3075 3950);
DISPLAY 0.872340 (-3075 3950);
PAINT AQUA (-3075 3950);
DISPLAY INVISIBLE (-3075 3950);
FORCEADD Q_CAP..1
(-2700 2625);
FORCEPROP 1 LAST LOCATION C2628
J 0
(-2650 2725);
DISPLAY 0.489362 (-2650 2725);
PAINT SKYBLUE (-2650 2725);
FORCEPROP 2 LAST $SEC 1
J 0
(-2650 2825);
DISPLAY 0.680851 (-2650 2825);
PAINT MONO (-2650 2825);
DISPLAY INVISIBLE (-2650 2825);
FORCEPROP 2 LAST CDS_SEC 1
J 0
(-2650 2825);
DISPLAY 1.021277 (-2650 2825);
DISPLAY INVISIBLE (-2650 2825);
FORCEPROP 1 LASTPIN (-2700 2725) $PN 1
J 0
(-2690 2705);
DISPLAY 0.489362 (-2690 2705);
FORCEPROP 1 LASTPIN (-2700 2525) $PN 2
J 0
(-2690 2505);
DISPLAY 0.489362 (-2690 2505);
FORCEPROP 1 LAST MATERIAL X6S
J 0
(-2650 2525);
DISPLAY 0.489362 (-2650 2525);
PAINT SKYBLUE (-2650 2525);
FORCEPROP 1 LAST TOLERANCE 20%
J 0
(-2650 2575);
DISPLAY 0.489362 (-2650 2575);
PAINT SKYBLUE (-2650 2575);
FORCEPROP 1 LAST VALUE 22UF
J 0
(-2650 2675);
DISPLAY 0.489362 (-2650 2675);
PAINT SKYBLUE (-2650 2675);
FORCEPROP 1 LAST VOLTAGE 4V
J 0
(-2650 2625);
DISPLAY 0.489362 (-2650 2625);
PAINT SKYBLUE (-2650 2625);
FORCEPROP 1 LAST PACK_TYPE C0402
J 0
(-2650 2425);
DISPLAY 0.489362 (-2650 2425);
PAINT SKYBLUE (-2650 2425);
FORCEPROP 2 LAST CDS_LIB pure_quanta
J 0
(-2700 2625);
PAINT MONO (-2700 2625);
DISPLAY INVISIBLE (-2700 2625);
FORCEPROP 1 LAST PATH I129
J 0
(-2650 2775);
DISPLAY 0.978723 (-2650 2775);
PAINT WHITE (-2650 2775);
DISPLAY INVISIBLE (-2650 2775);
FORCEPROP 1 LAST PART_NUMBER CH622KMEB02
J 0
(-2650 2475);
DISPLAY 0.489362 (-2650 2475);
PAINT SKYBLUE (-2650 2475);
DISPLAY INVISIBLE (-2650 2475);
FORCEADD Q_CAP..1
(-9075 3725);
FORCEPROP 1 LAST LOCATION C2530
J 0
(-9025 3825);
DISPLAY 0.489362 (-9025 3825);
PAINT SKYBLUE (-9025 3825);
FORCEPROP 2 LAST $SEC 1
J 0
(-9025 3925);
DISPLAY 0.680851 (-9025 3925);
PAINT MONO (-9025 3925);
DISPLAY INVISIBLE (-9025 3925);
FORCEPROP 2 LAST CDS_SEC 1
J 0
(-9025 3925);
DISPLAY 1.021277 (-9025 3925);
DISPLAY INVISIBLE (-9025 3925);
FORCEPROP 1 LASTPIN (-9075 3825) $PN 1
J 0
(-9065 3805);
DISPLAY 0.489362 (-9065 3805);
FORCEPROP 1 LASTPIN (-9075 3625) $PN 2
J 0
(-9065 3605);
DISPLAY 0.489362 (-9065 3605);
FORCEPROP 1 LAST MATERIAL X6S
J 0
(-9025 3625);
DISPLAY 0.489362 (-9025 3625);
PAINT SKYBLUE (-9025 3625);
FORCEPROP 1 LAST TOLERANCE 20%
J 0
(-9025 3675);
DISPLAY 0.489362 (-9025 3675);
PAINT SKYBLUE (-9025 3675);
FORCEPROP 1 LAST VALUE 22UF
J 0
(-9025 3775);
DISPLAY 0.489362 (-9025 3775);
PAINT SKYBLUE (-9025 3775);
FORCEPROP 1 LAST VOLTAGE 4V
J 0
(-9025 3725);
DISPLAY 0.489362 (-9025 3725);
PAINT SKYBLUE (-9025 3725);
FORCEPROP 1 LAST PACK_TYPE C0402
J 0
(-9025 3525);
DISPLAY 0.489362 (-9025 3525);
PAINT SKYBLUE (-9025 3525);
FORCEPROP 2 LAST CDS_LIB pure_quanta
J 0
(-9075 3725);
PAINT MONO (-9075 3725);
DISPLAY INVISIBLE (-9075 3725);
FORCEPROP 1 LAST PATH I13
J 0
(-9025 3875);
DISPLAY 0.978723 (-9025 3875);
PAINT WHITE (-9025 3875);
DISPLAY INVISIBLE (-9025 3875);
FORCEPROP 1 LAST PART_NUMBER CH622KMEB02
J 0
(-9025 3575);
DISPLAY 0.489362 (-9025 3575);
PAINT SKYBLUE (-9025 3575);
DISPLAY INVISIBLE (-9025 3575);
FORCEADD Q_CAP..1
(-2250 2625);
FORCEPROP 1 LAST LOCATION C2634
J 0
(-2200 2725);
DISPLAY 0.489362 (-2200 2725);
PAINT SKYBLUE (-2200 2725);
FORCEPROP 2 LAST $SEC 1
J 0
(-2200 2825);
DISPLAY 0.680851 (-2200 2825);
PAINT MONO (-2200 2825);
DISPLAY INVISIBLE (-2200 2825);
FORCEPROP 2 LAST CDS_SEC 1
J 0
(-2200 2825);
DISPLAY 1.021277 (-2200 2825);
DISPLAY INVISIBLE (-2200 2825);
FORCEPROP 1 LASTPIN (-2250 2725) $PN 1
J 0
(-2240 2705);
DISPLAY 0.489362 (-2240 2705);
FORCEPROP 1 LASTPIN (-2250 2525) $PN 2
J 0
(-2240 2505);
DISPLAY 0.489362 (-2240 2505);
FORCEPROP 1 LAST MATERIAL X6S
J 0
(-2200 2525);
DISPLAY 0.489362 (-2200 2525);
PAINT SKYBLUE (-2200 2525);
FORCEPROP 1 LAST TOLERANCE 20%
J 0
(-2200 2575);
DISPLAY 0.489362 (-2200 2575);
PAINT SKYBLUE (-2200 2575);
FORCEPROP 1 LAST VALUE 22UF
J 0
(-2200 2675);
DISPLAY 0.489362 (-2200 2675);
PAINT SKYBLUE (-2200 2675);
FORCEPROP 1 LAST VOLTAGE 4V
J 0
(-2200 2625);
DISPLAY 0.489362 (-2200 2625);
PAINT SKYBLUE (-2200 2625);
FORCEPROP 1 LAST PACK_TYPE C0402
J 0
(-2200 2425);
DISPLAY 0.489362 (-2200 2425);
PAINT SKYBLUE (-2200 2425);
FORCEPROP 2 LAST CDS_LIB pure_quanta
J 0
(-2250 2625);
PAINT MONO (-2250 2625);
DISPLAY INVISIBLE (-2250 2625);
FORCEPROP 1 LAST PATH I130
J 0
(-2200 2775);
DISPLAY 0.978723 (-2200 2775);
PAINT WHITE (-2200 2775);
DISPLAY INVISIBLE (-2200 2775);
FORCEPROP 1 LAST PART_NUMBER CH622KMEB02
J 0
(-2200 2475);
DISPLAY 0.489362 (-2200 2475);
PAINT SKYBLUE (-2200 2475);
DISPLAY INVISIBLE (-2200 2475);
FORCEADD Q_CAP..1
(-2700 3275);
FORCEPROP 1 LAST LOCATION C2627
J 0
(-2650 3375);
DISPLAY 0.489362 (-2650 3375);
PAINT SKYBLUE (-2650 3375);
FORCEPROP 2 LAST $SEC 1
J 0
(-2650 3475);
DISPLAY 0.680851 (-2650 3475);
PAINT MONO (-2650 3475);
DISPLAY INVISIBLE (-2650 3475);
FORCEPROP 2 LAST CDS_SEC 1
J 0
(-2650 3475);
DISPLAY 1.021277 (-2650 3475);
DISPLAY INVISIBLE (-2650 3475);
FORCEPROP 1 LASTPIN (-2700 3375) $PN 1
J 0
(-2690 3355);
DISPLAY 0.489362 (-2690 3355);
FORCEPROP 1 LASTPIN (-2700 3175) $PN 2
J 0
(-2690 3155);
DISPLAY 0.489362 (-2690 3155);
FORCEPROP 1 LAST MATERIAL X6S
J 0
(-2650 3175);
DISPLAY 0.489362 (-2650 3175);
PAINT SKYBLUE (-2650 3175);
FORCEPROP 1 LAST TOLERANCE 20%
J 0
(-2650 3225);
DISPLAY 0.489362 (-2650 3225);
PAINT SKYBLUE (-2650 3225);
FORCEPROP 1 LAST VALUE 22UF
J 0
(-2650 3325);
DISPLAY 0.489362 (-2650 3325);
PAINT SKYBLUE (-2650 3325);
FORCEPROP 1 LAST VOLTAGE 4V
J 0
(-2650 3275);
DISPLAY 0.489362 (-2650 3275);
PAINT SKYBLUE (-2650 3275);
FORCEPROP 1 LAST PACK_TYPE C0402
J 0
(-2650 3075);
DISPLAY 0.489362 (-2650 3075);
PAINT SKYBLUE (-2650 3075);
FORCEPROP 2 LAST CDS_LIB pure_quanta
J 0
(-2700 3275);
PAINT MONO (-2700 3275);
DISPLAY INVISIBLE (-2700 3275);
FORCEPROP 1 LAST PATH I131
J 0
(-2650 3425);
DISPLAY 0.978723 (-2650 3425);
PAINT WHITE (-2650 3425);
DISPLAY INVISIBLE (-2650 3425);
FORCEPROP 1 LAST PART_NUMBER CH622KMEB02
J 0
(-2650 3125);
DISPLAY 0.489362 (-2650 3125);
PAINT SKYBLUE (-2650 3125);
DISPLAY INVISIBLE (-2650 3125);
FORCEADD Q_CAP..1
(-2250 3275);
FORCEPROP 1 LAST LOCATION C2633
J 0
(-2200 3375);
DISPLAY 0.489362 (-2200 3375);
PAINT SKYBLUE (-2200 3375);
FORCEPROP 2 LAST $SEC 1
J 0
(-2200 3475);
DISPLAY 0.680851 (-2200 3475);
PAINT MONO (-2200 3475);
DISPLAY INVISIBLE (-2200 3475);
FORCEPROP 2 LAST CDS_SEC 1
J 0
(-2200 3475);
DISPLAY 1.021277 (-2200 3475);
DISPLAY INVISIBLE (-2200 3475);
FORCEPROP 1 LASTPIN (-2250 3375) $PN 1
J 0
(-2240 3355);
DISPLAY 0.489362 (-2240 3355);
FORCEPROP 1 LASTPIN (-2250 3175) $PN 2
J 0
(-2240 3155);
DISPLAY 0.489362 (-2240 3155);
FORCEPROP 1 LAST MATERIAL X6S
J 0
(-2200 3175);
DISPLAY 0.489362 (-2200 3175);
PAINT SKYBLUE (-2200 3175);
FORCEPROP 1 LAST TOLERANCE 20%
J 0
(-2200 3225);
DISPLAY 0.489362 (-2200 3225);
PAINT SKYBLUE (-2200 3225);
FORCEPROP 1 LAST VALUE 22UF
J 0
(-2200 3325);
DISPLAY 0.489362 (-2200 3325);
PAINT SKYBLUE (-2200 3325);
FORCEPROP 1 LAST VOLTAGE 4V
J 0
(-2200 3275);
DISPLAY 0.489362 (-2200 3275);
PAINT SKYBLUE (-2200 3275);
FORCEPROP 1 LAST PACK_TYPE C0402
J 0
(-2200 3075);
DISPLAY 0.489362 (-2200 3075);
PAINT SKYBLUE (-2200 3075);
FORCEPROP 2 LAST CDS_LIB pure_quanta
J 0
(-2250 3275);
PAINT MONO (-2250 3275);
DISPLAY INVISIBLE (-2250 3275);
FORCEPROP 1 LAST PATH I132
J 0
(-2200 3425);
DISPLAY 0.978723 (-2200 3425);
PAINT WHITE (-2200 3425);
DISPLAY INVISIBLE (-2200 3425);
FORCEPROP 1 LAST PART_NUMBER CH622KMEB02
J 0
(-2200 3125);
DISPLAY 0.489362 (-2200 3125);
PAINT SKYBLUE (-2200 3125);
DISPLAY INVISIBLE (-2200 3125);
FORCEADD Q_CAP..1
(-1800 1400);
FORCEPROP 1 LAST LOCATION C2642
J 0
(-1750 1500);
DISPLAY 0.489362 (-1750 1500);
PAINT SKYBLUE (-1750 1500);
FORCEPROP 2 LAST $SEC 1
J 0
(-1750 1600);
DISPLAY 0.680851 (-1750 1600);
PAINT MONO (-1750 1600);
DISPLAY INVISIBLE (-1750 1600);
FORCEPROP 2 LAST CDS_SEC 1
J 0
(-1750 1600);
DISPLAY 1.021277 (-1750 1600);
DISPLAY INVISIBLE (-1750 1600);
FORCEPROP 1 LASTPIN (-1800 1500) $PN 1
J 0
(-1790 1480);
DISPLAY 0.489362 (-1790 1480);
FORCEPROP 1 LASTPIN (-1800 1300) $PN 2
J 0
(-1790 1280);
DISPLAY 0.489362 (-1790 1280);
FORCEPROP 1 LAST MATERIAL X6S
J 0
(-1750 1300);
DISPLAY 0.489362 (-1750 1300);
PAINT SKYBLUE (-1750 1300);
FORCEPROP 1 LAST TOLERANCE 20%
J 0
(-1750 1350);
DISPLAY 0.489362 (-1750 1350);
PAINT SKYBLUE (-1750 1350);
FORCEPROP 1 LAST VALUE 22UF
J 0
(-1750 1450);
DISPLAY 0.489362 (-1750 1450);
PAINT SKYBLUE (-1750 1450);
FORCEPROP 1 LAST VOLTAGE 4V
J 0
(-1750 1400);
DISPLAY 0.489362 (-1750 1400);
PAINT SKYBLUE (-1750 1400);
FORCEPROP 1 LAST PACK_TYPE C0402
J 0
(-1750 1200);
DISPLAY 0.489362 (-1750 1200);
PAINT SKYBLUE (-1750 1200);
FORCEPROP 2 LAST CDS_LIB pure_quanta
J 0
(-1800 1400);
PAINT MONO (-1800 1400);
DISPLAY INVISIBLE (-1800 1400);
FORCEPROP 1 LAST PATH I133
J 0
(-1750 1550);
DISPLAY 0.978723 (-1750 1550);
PAINT WHITE (-1750 1550);
DISPLAY INVISIBLE (-1750 1550);
FORCEPROP 1 LAST PART_NUMBER CH622KMEB02
J 0
(-1750 1250);
DISPLAY 0.489362 (-1750 1250);
PAINT SKYBLUE (-1750 1250);
DISPLAY INVISIBLE (-1750 1250);
FORCEADD Q_CAP..1
(-1800 2000);
FORCEPROP 1 LAST LOCATION C2641
J 0
(-1750 2100);
DISPLAY 0.489362 (-1750 2100);
PAINT SKYBLUE (-1750 2100);
FORCEPROP 2 LAST $SEC 1
J 0
(-1750 2200);
DISPLAY 0.680851 (-1750 2200);
PAINT MONO (-1750 2200);
DISPLAY INVISIBLE (-1750 2200);
FORCEPROP 2 LAST CDS_SEC 1
J 0
(-1750 2200);
DISPLAY 1.021277 (-1750 2200);
DISPLAY INVISIBLE (-1750 2200);
FORCEPROP 1 LASTPIN (-1800 2100) $PN 1
J 0
(-1790 2080);
DISPLAY 0.489362 (-1790 2080);
FORCEPROP 1 LASTPIN (-1800 1900) $PN 2
J 0
(-1790 1880);
DISPLAY 0.489362 (-1790 1880);
FORCEPROP 1 LAST MATERIAL X6S
J 0
(-1750 1900);
DISPLAY 0.489362 (-1750 1900);
PAINT SKYBLUE (-1750 1900);
FORCEPROP 1 LAST TOLERANCE 20%
J 0
(-1750 1950);
DISPLAY 0.489362 (-1750 1950);
PAINT SKYBLUE (-1750 1950);
FORCEPROP 1 LAST VALUE 22UF
J 0
(-1750 2050);
DISPLAY 0.489362 (-1750 2050);
PAINT SKYBLUE (-1750 2050);
FORCEPROP 1 LAST VOLTAGE 4V
J 0
(-1750 2000);
DISPLAY 0.489362 (-1750 2000);
PAINT SKYBLUE (-1750 2000);
FORCEPROP 1 LAST PACK_TYPE C0402
J 0
(-1750 1800);
DISPLAY 0.489362 (-1750 1800);
PAINT SKYBLUE (-1750 1800);
FORCEPROP 2 LAST CDS_LIB pure_quanta
J 0
(-1800 2000);
PAINT MONO (-1800 2000);
DISPLAY INVISIBLE (-1800 2000);
FORCEPROP 1 LAST PATH I134
J 0
(-1750 2150);
DISPLAY 0.978723 (-1750 2150);
PAINT WHITE (-1750 2150);
DISPLAY INVISIBLE (-1750 2150);
FORCEPROP 1 LAST PART_NUMBER CH622KMEB02
J 0
(-1750 1850);
DISPLAY 0.489362 (-1750 1850);
PAINT SKYBLUE (-1750 1850);
DISPLAY INVISIBLE (-1750 1850);
FORCEADD Q_CAP..1
(-1350 1400);
FORCEPROP 1 LAST LOCATION C2648
J 0
(-1300 1500);
DISPLAY 0.489362 (-1300 1500);
PAINT SKYBLUE (-1300 1500);
FORCEPROP 2 LAST $SEC 1
J 0
(-1300 1600);
DISPLAY 0.680851 (-1300 1600);
PAINT MONO (-1300 1600);
DISPLAY INVISIBLE (-1300 1600);
FORCEPROP 2 LAST CDS_SEC 1
J 0
(-1300 1600);
DISPLAY 1.021277 (-1300 1600);
DISPLAY INVISIBLE (-1300 1600);
FORCEPROP 1 LASTPIN (-1350 1500) $PN 1
J 0
(-1340 1480);
DISPLAY 0.489362 (-1340 1480);
FORCEPROP 1 LASTPIN (-1350 1300) $PN 2
J 0
(-1340 1280);
DISPLAY 0.489362 (-1340 1280);
FORCEPROP 1 LAST MATERIAL X6S
J 0
(-1300 1300);
DISPLAY 0.489362 (-1300 1300);
PAINT SKYBLUE (-1300 1300);
FORCEPROP 1 LAST TOLERANCE 20%
J 0
(-1300 1350);
DISPLAY 0.489362 (-1300 1350);
PAINT SKYBLUE (-1300 1350);
FORCEPROP 1 LAST VALUE 22UF
J 0
(-1300 1450);
DISPLAY 0.489362 (-1300 1450);
PAINT SKYBLUE (-1300 1450);
FORCEPROP 1 LAST VOLTAGE 4V
J 0
(-1300 1400);
DISPLAY 0.489362 (-1300 1400);
PAINT SKYBLUE (-1300 1400);
FORCEPROP 1 LAST PACK_TYPE C0402
J 0
(-1300 1200);
DISPLAY 0.489362 (-1300 1200);
PAINT SKYBLUE (-1300 1200);
FORCEPROP 2 LAST CDS_LIB pure_quanta
J 0
(-1350 1400);
PAINT MONO (-1350 1400);
DISPLAY INVISIBLE (-1350 1400);
FORCEPROP 1 LAST PATH I135
J 0
(-1300 1550);
DISPLAY 0.978723 (-1300 1550);
PAINT WHITE (-1300 1550);
DISPLAY INVISIBLE (-1300 1550);
FORCEPROP 1 LAST PART_NUMBER CH622KMEB02
J 0
(-1300 1250);
DISPLAY 0.489362 (-1300 1250);
PAINT SKYBLUE (-1300 1250);
DISPLAY INVISIBLE (-1300 1250);
FORCEADD Q_CAP..1
(-1350 2000);
FORCEPROP 1 LAST LOCATION C2647
J 0
(-1300 2100);
DISPLAY 0.489362 (-1300 2100);
PAINT SKYBLUE (-1300 2100);
FORCEPROP 2 LAST $SEC 1
J 0
(-1300 2200);
DISPLAY 0.680851 (-1300 2200);
PAINT MONO (-1300 2200);
DISPLAY INVISIBLE (-1300 2200);
FORCEPROP 2 LAST CDS_SEC 1
J 0
(-1300 2200);
DISPLAY 1.021277 (-1300 2200);
DISPLAY INVISIBLE (-1300 2200);
FORCEPROP 1 LASTPIN (-1350 2100) $PN 1
J 0
(-1340 2080);
DISPLAY 0.489362 (-1340 2080);
FORCEPROP 1 LASTPIN (-1350 1900) $PN 2
J 0
(-1340 1880);
DISPLAY 0.489362 (-1340 1880);
FORCEPROP 1 LAST MATERIAL X6S
J 0
(-1300 1900);
DISPLAY 0.489362 (-1300 1900);
PAINT SKYBLUE (-1300 1900);
FORCEPROP 1 LAST TOLERANCE 20%
J 0
(-1300 1950);
DISPLAY 0.489362 (-1300 1950);
PAINT SKYBLUE (-1300 1950);
FORCEPROP 1 LAST VALUE 22UF
J 0
(-1300 2050);
DISPLAY 0.489362 (-1300 2050);
PAINT SKYBLUE (-1300 2050);
FORCEPROP 1 LAST VOLTAGE 4V
J 0
(-1300 2000);
DISPLAY 0.489362 (-1300 2000);
PAINT SKYBLUE (-1300 2000);
FORCEPROP 1 LAST PACK_TYPE C0402
J 0
(-1300 1800);
DISPLAY 0.489362 (-1300 1800);
PAINT SKYBLUE (-1300 1800);
FORCEPROP 2 LAST CDS_LIB pure_quanta
J 0
(-1350 2000);
PAINT MONO (-1350 2000);
DISPLAY INVISIBLE (-1350 2000);
FORCEPROP 1 LAST PATH I136
J 0
(-1300 2150);
DISPLAY 0.978723 (-1300 2150);
PAINT WHITE (-1300 2150);
DISPLAY INVISIBLE (-1300 2150);
FORCEPROP 1 LAST PART_NUMBER CH622KMEB02
J 0
(-1300 1850);
DISPLAY 0.489362 (-1300 1850);
PAINT SKYBLUE (-1300 1850);
DISPLAY INVISIBLE (-1300 1850);
FORCEADD UNIVERSAL_GND..1
(-500 1025);
FORCEPROP 3 LASTPIN (-500 1075) SIG_NAME GND\g
J 0
(-490 1085);
DISPLAY 0.659574 (-490 1085);
PAINT MONO (-490 1085);
DISPLAY INVISIBLE (-490 1085);
FORCEPROP 2 LAST CDS_LIB pure_quanta_power
J 0
(-500 1025);
PAINT MONO (-500 1025);
DISPLAY INVISIBLE (-500 1025);
FORCEPROP 1 LAST HDL_POWER GND
J 1
(-475 950);
DISPLAY 0.872340 (-475 950);
PAINT GREEN (-475 950);
DISPLAY INVISIBLE (-475 950);
FORCEPROP 1 LAST PATH I137
J 0
(-425 1025);
DISPLAY 0.872340 (-425 1025);
PAINT AQUA (-425 1025);
DISPLAY INVISIBLE (-425 1025);
FORCEADD Q_CAP..1
(-900 1400);
FORCEPROP 1 LAST LOCATION C3934
J 0
(-850 1500);
DISPLAY 0.489362 (-850 1500);
PAINT SKYBLUE (-850 1500);
FORCEPROP 2 LAST $SEC 1
J 0
(-850 1600);
DISPLAY 0.680851 (-850 1600);
PAINT MONO (-850 1600);
DISPLAY INVISIBLE (-850 1600);
FORCEPROP 2 LAST CDS_SEC 1
J 0
(-850 1600);
DISPLAY 1.021277 (-850 1600);
DISPLAY INVISIBLE (-850 1600);
FORCEPROP 1 LASTPIN (-900 1500) $PN 1
J 0
(-890 1480);
DISPLAY 0.489362 (-890 1480);
FORCEPROP 1 LASTPIN (-900 1300) $PN 2
J 0
(-890 1280);
DISPLAY 0.489362 (-890 1280);
FORCEPROP 1 LAST MATERIAL X6S
J 0
(-850 1300);
DISPLAY 0.489362 (-850 1300);
PAINT SKYBLUE (-850 1300);
FORCEPROP 1 LAST TOLERANCE 20%
J 0
(-850 1350);
DISPLAY 0.489362 (-850 1350);
PAINT SKYBLUE (-850 1350);
FORCEPROP 1 LAST VALUE 22UF
J 0
(-850 1450);
DISPLAY 0.489362 (-850 1450);
PAINT SKYBLUE (-850 1450);
FORCEPROP 1 LAST VOLTAGE 4V
J 0
(-850 1400);
DISPLAY 0.489362 (-850 1400);
PAINT SKYBLUE (-850 1400);
FORCEPROP 1 LAST PACK_TYPE C0402
J 0
(-850 1200);
DISPLAY 0.489362 (-850 1200);
PAINT SKYBLUE (-850 1200);
FORCEPROP 2 LAST CDS_LIB pure_quanta
J 0
(-900 1400);
PAINT MONO (-900 1400);
DISPLAY INVISIBLE (-900 1400);
FORCEPROP 1 LAST PATH I138
J 0
(-850 1550);
DISPLAY 0.978723 (-850 1550);
PAINT WHITE (-850 1550);
DISPLAY INVISIBLE (-850 1550);
FORCEPROP 1 LAST PART_NUMBER CH622KMEB02
J 0
(-850 1250);
DISPLAY 0.489362 (-850 1250);
PAINT SKYBLUE (-850 1250);
DISPLAY INVISIBLE (-850 1250);
FORCEADD Q_CAP..1
(-900 2000);
FORCEPROP 1 LAST LOCATION C2653
J 0
(-850 2100);
DISPLAY 0.489362 (-850 2100);
PAINT SKYBLUE (-850 2100);
FORCEPROP 2 LAST $SEC 1
J 0
(-850 2200);
DISPLAY 0.680851 (-850 2200);
PAINT MONO (-850 2200);
DISPLAY INVISIBLE (-850 2200);
FORCEPROP 2 LAST CDS_SEC 1
J 0
(-850 2200);
DISPLAY 1.021277 (-850 2200);
DISPLAY INVISIBLE (-850 2200);
FORCEPROP 1 LASTPIN (-900 2100) $PN 1
J 0
(-890 2080);
DISPLAY 0.489362 (-890 2080);
FORCEPROP 1 LASTPIN (-900 1900) $PN 2
J 0
(-890 1880);
DISPLAY 0.489362 (-890 1880);
FORCEPROP 1 LAST MATERIAL X6S
J 0
(-850 1900);
DISPLAY 0.489362 (-850 1900);
PAINT SKYBLUE (-850 1900);
FORCEPROP 1 LAST TOLERANCE 20%
J 0
(-850 1950);
DISPLAY 0.489362 (-850 1950);
PAINT SKYBLUE (-850 1950);
FORCEPROP 1 LAST VALUE 22UF
J 0
(-850 2050);
DISPLAY 0.489362 (-850 2050);
PAINT SKYBLUE (-850 2050);
FORCEPROP 1 LAST VOLTAGE 4V
J 0
(-850 2000);
DISPLAY 0.489362 (-850 2000);
PAINT SKYBLUE (-850 2000);
FORCEPROP 1 LAST PACK_TYPE C0402
J 0
(-850 1800);
DISPLAY 0.489362 (-850 1800);
PAINT SKYBLUE (-850 1800);
FORCEPROP 2 LAST CDS_LIB pure_quanta
J 0
(-900 2000);
PAINT MONO (-900 2000);
DISPLAY INVISIBLE (-900 2000);
FORCEPROP 1 LAST PATH I139
J 0
(-850 2150);
DISPLAY 0.978723 (-850 2150);
PAINT WHITE (-850 2150);
DISPLAY INVISIBLE (-850 2150);
FORCEPROP 1 LAST PART_NUMBER CH622KMEB02
J 0
(-850 1850);
DISPLAY 0.489362 (-850 1850);
PAINT SKYBLUE (-850 1850);
DISPLAY INVISIBLE (-850 1850);
FORCEADD UNIVERSAL_POWER..1
(-9075 4000);
FORCEPROP 3 LASTPIN (-9075 3950) SIG_NAME PVDDCR_SOC_P0\g
J 0
(-9065 3960);
DISPLAY 0.659574 (-9065 3960);
PAINT MONO (-9065 3960);
DISPLAY INVISIBLE (-9065 3960);
FORCEPROP 1 LAST HDL_POWER PVDDCR_SOC_P0
J 1
(-9075 4050);
DISPLAY 0.489362 (-9075 4050);
PAINT GREEN (-9075 4050);
FORCEPROP 2 LAST CDS_LIB pure_quanta_power
J 0
(-9075 4000);
DISPLAY INVISIBLE (-9075 4000);
FORCEPROP 1 LAST PATH I14
J 0
(-9025 4025);
DISPLAY 0.872340 (-9025 4025);
PAINT AQUA (-9025 4025);
DISPLAY INVISIBLE (-9025 4025);
FORCEADD Q_CAP..1
(-500 1400);
FORCEPROP 1 LAST LOCATION C3935
J 0
(-450 1500);
DISPLAY 0.489362 (-450 1500);
PAINT SKYBLUE (-450 1500);
FORCEPROP 2 LAST $SEC 1
J 0
(-450 1600);
DISPLAY 0.680851 (-450 1600);
PAINT MONO (-450 1600);
DISPLAY INVISIBLE (-450 1600);
FORCEPROP 2 LAST CDS_SEC 1
J 0
(-450 1600);
DISPLAY 1.021277 (-450 1600);
DISPLAY INVISIBLE (-450 1600);
FORCEPROP 1 LASTPIN (-500 1500) $PN 1
J 0
(-490 1480);
DISPLAY 0.489362 (-490 1480);
FORCEPROP 1 LASTPIN (-500 1300) $PN 2
J 0
(-490 1280);
DISPLAY 0.489362 (-490 1280);
FORCEPROP 1 LAST MATERIAL X6S
J 0
(-450 1300);
DISPLAY 0.489362 (-450 1300);
PAINT SKYBLUE (-450 1300);
FORCEPROP 1 LAST TOLERANCE 20%
J 0
(-450 1350);
DISPLAY 0.489362 (-450 1350);
PAINT SKYBLUE (-450 1350);
FORCEPROP 1 LAST VALUE 22UF
J 0
(-450 1450);
DISPLAY 0.489362 (-450 1450);
PAINT SKYBLUE (-450 1450);
FORCEPROP 1 LAST VOLTAGE 4V
J 0
(-450 1400);
DISPLAY 0.489362 (-450 1400);
PAINT SKYBLUE (-450 1400);
FORCEPROP 1 LAST PACK_TYPE C0402
J 0
(-450 1200);
DISPLAY 0.489362 (-450 1200);
PAINT SKYBLUE (-450 1200);
FORCEPROP 2 LAST CDS_LIB pure_quanta
J 0
(-500 1400);
PAINT MONO (-500 1400);
DISPLAY INVISIBLE (-500 1400);
FORCEPROP 1 LAST PATH I140
J 0
(-450 1550);
DISPLAY 0.978723 (-450 1550);
PAINT WHITE (-450 1550);
DISPLAY INVISIBLE (-450 1550);
FORCEPROP 1 LAST PART_NUMBER CH622KMEB02
J 0
(-450 1250);
DISPLAY 0.489362 (-450 1250);
PAINT SKYBLUE (-450 1250);
DISPLAY INVISIBLE (-450 1250);
FORCEADD UNIVERSAL_GND..1
(-500 1625);
FORCEPROP 3 LASTPIN (-500 1675) SIG_NAME GND\g
J 0
(-490 1685);
DISPLAY 0.659574 (-490 1685);
PAINT MONO (-490 1685);
DISPLAY INVISIBLE (-490 1685);
FORCEPROP 2 LAST CDS_LIB pure_quanta_power
J 0
(-500 1625);
PAINT MONO (-500 1625);
DISPLAY INVISIBLE (-500 1625);
FORCEPROP 1 LAST HDL_POWER GND
J 1
(-475 1550);
DISPLAY 0.872340 (-475 1550);
PAINT GREEN (-475 1550);
DISPLAY INVISIBLE (-475 1550);
FORCEPROP 1 LAST PATH I141
J 0
(-425 1625);
DISPLAY 0.872340 (-425 1625);
PAINT AQUA (-425 1625);
DISPLAY INVISIBLE (-425 1625);
FORCEADD Q_CAP..1
(-500 2000);
FORCEPROP 1 LAST LOCATION C2658
J 0
(-450 2100);
DISPLAY 0.489362 (-450 2100);
PAINT SKYBLUE (-450 2100);
FORCEPROP 2 LAST $SEC 1
J 0
(-450 2200);
DISPLAY 0.680851 (-450 2200);
PAINT MONO (-450 2200);
DISPLAY INVISIBLE (-450 2200);
FORCEPROP 2 LAST CDS_SEC 1
J 0
(-450 2200);
DISPLAY 1.021277 (-450 2200);
DISPLAY INVISIBLE (-450 2200);
FORCEPROP 1 LASTPIN (-500 2100) $PN 1
J 0
(-490 2080);
DISPLAY 0.489362 (-490 2080);
FORCEPROP 1 LASTPIN (-500 1900) $PN 2
J 0
(-490 1880);
DISPLAY 0.489362 (-490 1880);
FORCEPROP 1 LAST MATERIAL X6S
J 0
(-450 1900);
DISPLAY 0.489362 (-450 1900);
PAINT SKYBLUE (-450 1900);
FORCEPROP 1 LAST TOLERANCE 20%
J 0
(-450 1950);
DISPLAY 0.489362 (-450 1950);
PAINT SKYBLUE (-450 1950);
FORCEPROP 1 LAST VALUE 22UF
J 0
(-450 2050);
DISPLAY 0.489362 (-450 2050);
PAINT SKYBLUE (-450 2050);
FORCEPROP 1 LAST VOLTAGE 4V
J 0
(-450 2000);
DISPLAY 0.489362 (-450 2000);
PAINT SKYBLUE (-450 2000);
FORCEPROP 1 LAST PACK_TYPE C0402
J 0
(-450 1800);
DISPLAY 0.489362 (-450 1800);
PAINT SKYBLUE (-450 1800);
FORCEPROP 2 LAST CDS_LIB pure_quanta
J 0
(-500 2000);
PAINT MONO (-500 2000);
DISPLAY INVISIBLE (-500 2000);
FORCEPROP 1 LAST PATH I142
J 0
(-450 2150);
DISPLAY 0.978723 (-450 2150);
PAINT WHITE (-450 2150);
DISPLAY INVISIBLE (-450 2150);
FORCEPROP 1 LAST PART_NUMBER CH622KMEB02
J 0
(-450 1850);
DISPLAY 0.489362 (-450 1850);
PAINT SKYBLUE (-450 1850);
DISPLAY INVISIBLE (-450 1850);
FORCEADD Q_CAP..1
(-1800 2625);
FORCEPROP 1 LAST LOCATION C2640
J 0
(-1750 2725);
DISPLAY 0.489362 (-1750 2725);
PAINT SKYBLUE (-1750 2725);
FORCEPROP 2 LAST $SEC 1
J 0
(-1750 2825);
DISPLAY 0.680851 (-1750 2825);
PAINT MONO (-1750 2825);
DISPLAY INVISIBLE (-1750 2825);
FORCEPROP 2 LAST CDS_SEC 1
J 0
(-1750 2825);
DISPLAY 1.021277 (-1750 2825);
DISPLAY INVISIBLE (-1750 2825);
FORCEPROP 1 LASTPIN (-1800 2725) $PN 1
J 0
(-1790 2705);
DISPLAY 0.489362 (-1790 2705);
FORCEPROP 1 LASTPIN (-1800 2525) $PN 2
J 0
(-1790 2505);
DISPLAY 0.489362 (-1790 2505);
FORCEPROP 1 LAST MATERIAL X6S
J 0
(-1750 2525);
DISPLAY 0.489362 (-1750 2525);
PAINT SKYBLUE (-1750 2525);
FORCEPROP 1 LAST TOLERANCE 20%
J 0
(-1750 2575);
DISPLAY 0.489362 (-1750 2575);
PAINT SKYBLUE (-1750 2575);
FORCEPROP 1 LAST VALUE 22UF
J 0
(-1750 2675);
DISPLAY 0.489362 (-1750 2675);
PAINT SKYBLUE (-1750 2675);
FORCEPROP 1 LAST VOLTAGE 4V
J 0
(-1750 2625);
DISPLAY 0.489362 (-1750 2625);
PAINT SKYBLUE (-1750 2625);
FORCEPROP 1 LAST PACK_TYPE C0402
J 0
(-1750 2425);
DISPLAY 0.489362 (-1750 2425);
PAINT SKYBLUE (-1750 2425);
FORCEPROP 2 LAST CDS_LIB pure_quanta
J 0
(-1800 2625);
PAINT MONO (-1800 2625);
DISPLAY INVISIBLE (-1800 2625);
FORCEPROP 1 LAST PATH I143
J 0
(-1750 2775);
DISPLAY 0.978723 (-1750 2775);
PAINT WHITE (-1750 2775);
DISPLAY INVISIBLE (-1750 2775);
FORCEPROP 1 LAST PART_NUMBER CH622KMEB02
J 0
(-1750 2475);
DISPLAY 0.489362 (-1750 2475);
PAINT SKYBLUE (-1750 2475);
DISPLAY INVISIBLE (-1750 2475);
FORCEADD Q_CAP..1
(-1350 2625);
FORCEPROP 1 LAST LOCATION C2646
J 0
(-1300 2725);
DISPLAY 0.489362 (-1300 2725);
PAINT SKYBLUE (-1300 2725);
FORCEPROP 2 LAST $SEC 1
J 0
(-1300 2825);
DISPLAY 0.680851 (-1300 2825);
PAINT MONO (-1300 2825);
DISPLAY INVISIBLE (-1300 2825);
FORCEPROP 2 LAST CDS_SEC 1
J 0
(-1300 2825);
DISPLAY 1.021277 (-1300 2825);
DISPLAY INVISIBLE (-1300 2825);
FORCEPROP 1 LASTPIN (-1350 2725) $PN 1
J 0
(-1340 2705);
DISPLAY 0.489362 (-1340 2705);
FORCEPROP 1 LASTPIN (-1350 2525) $PN 2
J 0
(-1340 2505);
DISPLAY 0.489362 (-1340 2505);
FORCEPROP 1 LAST MATERIAL X6S
J 0
(-1300 2525);
DISPLAY 0.489362 (-1300 2525);
PAINT SKYBLUE (-1300 2525);
FORCEPROP 1 LAST TOLERANCE 20%
J 0
(-1300 2575);
DISPLAY 0.489362 (-1300 2575);
PAINT SKYBLUE (-1300 2575);
FORCEPROP 1 LAST VALUE 22UF
J 0
(-1300 2675);
DISPLAY 0.489362 (-1300 2675);
PAINT SKYBLUE (-1300 2675);
FORCEPROP 1 LAST VOLTAGE 4V
J 0
(-1300 2625);
DISPLAY 0.489362 (-1300 2625);
PAINT SKYBLUE (-1300 2625);
FORCEPROP 1 LAST PACK_TYPE C0402
J 0
(-1300 2425);
DISPLAY 0.489362 (-1300 2425);
PAINT SKYBLUE (-1300 2425);
FORCEPROP 2 LAST CDS_LIB pure_quanta
J 0
(-1350 2625);
PAINT MONO (-1350 2625);
DISPLAY INVISIBLE (-1350 2625);
FORCEPROP 1 LAST PATH I144
J 0
(-1300 2775);
DISPLAY 0.978723 (-1300 2775);
PAINT WHITE (-1300 2775);
DISPLAY INVISIBLE (-1300 2775);
FORCEPROP 1 LAST PART_NUMBER CH622KMEB02
J 0
(-1300 2475);
DISPLAY 0.489362 (-1300 2475);
PAINT SKYBLUE (-1300 2475);
DISPLAY INVISIBLE (-1300 2475);
FORCEADD Q_CAP..1
(-1800 3275);
FORCEPROP 1 LAST LOCATION C2639
J 0
(-1750 3375);
DISPLAY 0.489362 (-1750 3375);
PAINT SKYBLUE (-1750 3375);
FORCEPROP 2 LAST $SEC 1
J 0
(-1750 3475);
DISPLAY 0.680851 (-1750 3475);
PAINT MONO (-1750 3475);
DISPLAY INVISIBLE (-1750 3475);
FORCEPROP 2 LAST CDS_SEC 1
J 0
(-1750 3475);
DISPLAY 1.021277 (-1750 3475);
DISPLAY INVISIBLE (-1750 3475);
FORCEPROP 1 LASTPIN (-1800 3375) $PN 1
J 0
(-1790 3355);
DISPLAY 0.489362 (-1790 3355);
FORCEPROP 1 LASTPIN (-1800 3175) $PN 2
J 0
(-1790 3155);
DISPLAY 0.489362 (-1790 3155);
FORCEPROP 1 LAST MATERIAL X6S
J 0
(-1750 3175);
DISPLAY 0.489362 (-1750 3175);
PAINT SKYBLUE (-1750 3175);
FORCEPROP 1 LAST TOLERANCE 20%
J 0
(-1750 3225);
DISPLAY 0.489362 (-1750 3225);
PAINT SKYBLUE (-1750 3225);
FORCEPROP 1 LAST VALUE 22UF
J 0
(-1750 3325);
DISPLAY 0.489362 (-1750 3325);
PAINT SKYBLUE (-1750 3325);
FORCEPROP 1 LAST VOLTAGE 4V
J 0
(-1750 3275);
DISPLAY 0.489362 (-1750 3275);
PAINT SKYBLUE (-1750 3275);
FORCEPROP 1 LAST PACK_TYPE C0402
J 0
(-1750 3075);
DISPLAY 0.489362 (-1750 3075);
PAINT SKYBLUE (-1750 3075);
FORCEPROP 2 LAST CDS_LIB pure_quanta
J 0
(-1800 3275);
PAINT MONO (-1800 3275);
DISPLAY INVISIBLE (-1800 3275);
FORCEPROP 1 LAST PATH I145
J 0
(-1750 3425);
DISPLAY 0.978723 (-1750 3425);
PAINT WHITE (-1750 3425);
DISPLAY INVISIBLE (-1750 3425);
FORCEPROP 1 LAST PART_NUMBER CH622KMEB02
J 0
(-1750 3125);
DISPLAY 0.489362 (-1750 3125);
PAINT SKYBLUE (-1750 3125);
DISPLAY INVISIBLE (-1750 3125);
FORCEADD Q_CAP..1
(-1350 3275);
FORCEPROP 1 LAST LOCATION C2645
J 0
(-1300 3375);
DISPLAY 0.489362 (-1300 3375);
PAINT SKYBLUE (-1300 3375);
FORCEPROP 2 LAST $SEC 1
J 0
(-1300 3475);
DISPLAY 0.680851 (-1300 3475);
PAINT MONO (-1300 3475);
DISPLAY INVISIBLE (-1300 3475);
FORCEPROP 2 LAST CDS_SEC 1
J 0
(-1300 3475);
DISPLAY 1.021277 (-1300 3475);
DISPLAY INVISIBLE (-1300 3475);
FORCEPROP 1 LASTPIN (-1350 3375) $PN 1
J 0
(-1340 3355);
DISPLAY 0.489362 (-1340 3355);
FORCEPROP 1 LASTPIN (-1350 3175) $PN 2
J 0
(-1340 3155);
DISPLAY 0.489362 (-1340 3155);
FORCEPROP 1 LAST MATERIAL X6S
J 0
(-1300 3175);
DISPLAY 0.489362 (-1300 3175);
PAINT SKYBLUE (-1300 3175);
FORCEPROP 1 LAST TOLERANCE 20%
J 0
(-1300 3225);
DISPLAY 0.489362 (-1300 3225);
PAINT SKYBLUE (-1300 3225);
FORCEPROP 1 LAST VALUE 22UF
J 0
(-1300 3325);
DISPLAY 0.489362 (-1300 3325);
PAINT SKYBLUE (-1300 3325);
FORCEPROP 1 LAST VOLTAGE 4V
J 0
(-1300 3275);
DISPLAY 0.489362 (-1300 3275);
PAINT SKYBLUE (-1300 3275);
FORCEPROP 1 LAST PACK_TYPE C0402
J 0
(-1300 3075);
DISPLAY 0.489362 (-1300 3075);
PAINT SKYBLUE (-1300 3075);
FORCEPROP 2 LAST CDS_LIB pure_quanta
J 0
(-1350 3275);
PAINT MONO (-1350 3275);
DISPLAY INVISIBLE (-1350 3275);
FORCEPROP 1 LAST PATH I146
J 0
(-1300 3425);
DISPLAY 0.978723 (-1300 3425);
PAINT WHITE (-1300 3425);
DISPLAY INVISIBLE (-1300 3425);
FORCEPROP 1 LAST PART_NUMBER CH622KMEB02
J 0
(-1300 3125);
DISPLAY 0.489362 (-1300 3125);
PAINT SKYBLUE (-1300 3125);
DISPLAY INVISIBLE (-1300 3125);
FORCEADD Q_CAP..1
(-900 2625);
FORCEPROP 1 LAST LOCATION C2652
J 0
(-850 2725);
DISPLAY 0.489362 (-850 2725);
PAINT SKYBLUE (-850 2725);
FORCEPROP 2 LAST $SEC 1
J 0
(-850 2825);
DISPLAY 0.680851 (-850 2825);
PAINT MONO (-850 2825);
DISPLAY INVISIBLE (-850 2825);
FORCEPROP 2 LAST CDS_SEC 1
J 0
(-850 2825);
DISPLAY 1.021277 (-850 2825);
DISPLAY INVISIBLE (-850 2825);
FORCEPROP 1 LASTPIN (-900 2725) $PN 1
J 0
(-890 2705);
DISPLAY 0.489362 (-890 2705);
FORCEPROP 1 LASTPIN (-900 2525) $PN 2
J 0
(-890 2505);
DISPLAY 0.489362 (-890 2505);
FORCEPROP 1 LAST MATERIAL X6S
J 0
(-850 2525);
DISPLAY 0.489362 (-850 2525);
PAINT SKYBLUE (-850 2525);
FORCEPROP 1 LAST TOLERANCE 20%
J 0
(-850 2575);
DISPLAY 0.489362 (-850 2575);
PAINT SKYBLUE (-850 2575);
FORCEPROP 1 LAST VALUE 22UF
J 0
(-850 2675);
DISPLAY 0.489362 (-850 2675);
PAINT SKYBLUE (-850 2675);
FORCEPROP 1 LAST VOLTAGE 4V
J 0
(-850 2625);
DISPLAY 0.489362 (-850 2625);
PAINT SKYBLUE (-850 2625);
FORCEPROP 1 LAST PACK_TYPE C0402
J 0
(-850 2425);
DISPLAY 0.489362 (-850 2425);
PAINT SKYBLUE (-850 2425);
FORCEPROP 2 LAST CDS_LIB pure_quanta
J 0
(-900 2625);
PAINT MONO (-900 2625);
DISPLAY INVISIBLE (-900 2625);
FORCEPROP 1 LAST PATH I147
J 0
(-850 2775);
DISPLAY 0.978723 (-850 2775);
PAINT WHITE (-850 2775);
DISPLAY INVISIBLE (-850 2775);
FORCEPROP 1 LAST PART_NUMBER CH622KMEB02
J 0
(-850 2475);
DISPLAY 0.489362 (-850 2475);
PAINT SKYBLUE (-850 2475);
DISPLAY INVISIBLE (-850 2475);
FORCEADD UNIVERSAL_GND..1
(-500 2275);
FORCEPROP 3 LASTPIN (-500 2325) SIG_NAME GND\g
J 0
(-490 2335);
DISPLAY 0.659574 (-490 2335);
PAINT MONO (-490 2335);
DISPLAY INVISIBLE (-490 2335);
FORCEPROP 2 LAST CDS_LIB pure_quanta_power
J 0
(-500 2275);
PAINT MONO (-500 2275);
DISPLAY INVISIBLE (-500 2275);
FORCEPROP 1 LAST HDL_POWER GND
J 1
(-475 2200);
DISPLAY 0.872340 (-475 2200);
PAINT GREEN (-475 2200);
DISPLAY INVISIBLE (-475 2200);
FORCEPROP 1 LAST PATH I148
J 0
(-425 2275);
DISPLAY 0.872340 (-425 2275);
PAINT AQUA (-425 2275);
DISPLAY INVISIBLE (-425 2275);
FORCEADD Q_CAP..1
(-500 2625);
FORCEPROP 1 LAST LOCATION C2657
J 0
(-450 2725);
DISPLAY 0.489362 (-450 2725);
PAINT SKYBLUE (-450 2725);
FORCEPROP 2 LAST $SEC 1
J 0
(-450 2825);
DISPLAY 0.680851 (-450 2825);
PAINT MONO (-450 2825);
DISPLAY INVISIBLE (-450 2825);
FORCEPROP 2 LAST CDS_SEC 1
J 0
(-450 2825);
DISPLAY 1.021277 (-450 2825);
DISPLAY INVISIBLE (-450 2825);
FORCEPROP 1 LASTPIN (-500 2725) $PN 1
J 0
(-490 2705);
DISPLAY 0.489362 (-490 2705);
FORCEPROP 1 LASTPIN (-500 2525) $PN 2
J 0
(-490 2505);
DISPLAY 0.489362 (-490 2505);
FORCEPROP 1 LAST MATERIAL X6S
J 0
(-450 2525);
DISPLAY 0.489362 (-450 2525);
PAINT SKYBLUE (-450 2525);
FORCEPROP 1 LAST TOLERANCE 20%
J 0
(-450 2575);
DISPLAY 0.489362 (-450 2575);
PAINT SKYBLUE (-450 2575);
FORCEPROP 1 LAST VALUE 22UF
J 0
(-450 2675);
DISPLAY 0.489362 (-450 2675);
PAINT SKYBLUE (-450 2675);
FORCEPROP 1 LAST VOLTAGE 4V
J 0
(-450 2625);
DISPLAY 0.489362 (-450 2625);
PAINT SKYBLUE (-450 2625);
FORCEPROP 1 LAST PACK_TYPE C0402
J 0
(-450 2425);
DISPLAY 0.489362 (-450 2425);
PAINT SKYBLUE (-450 2425);
FORCEPROP 2 LAST CDS_LIB pure_quanta
J 0
(-500 2625);
PAINT MONO (-500 2625);
DISPLAY INVISIBLE (-500 2625);
FORCEPROP 1 LAST PATH I149
J 0
(-450 2775);
DISPLAY 0.978723 (-450 2775);
PAINT WHITE (-450 2775);
DISPLAY INVISIBLE (-450 2775);
FORCEPROP 1 LAST PART_NUMBER CH622KMEB02
J 0
(-450 2475);
DISPLAY 0.489362 (-450 2475);
PAINT SKYBLUE (-450 2475);
DISPLAY INVISIBLE (-450 2475);
FORCEADD Q_CAP..1
(-8625 3725);
FORCEPROP 1 LAST LOCATION C2537
J 0
(-8575 3825);
DISPLAY 0.489362 (-8575 3825);
PAINT SKYBLUE (-8575 3825);
FORCEPROP 2 LAST $SEC 1
J 0
(-8575 3925);
DISPLAY 0.680851 (-8575 3925);
PAINT MONO (-8575 3925);
DISPLAY INVISIBLE (-8575 3925);
FORCEPROP 2 LAST CDS_SEC 1
J 0
(-8575 3925);
DISPLAY 1.021277 (-8575 3925);
DISPLAY INVISIBLE (-8575 3925);
FORCEPROP 1 LASTPIN (-8625 3825) $PN 1
J 0
(-8615 3805);
DISPLAY 0.489362 (-8615 3805);
FORCEPROP 1 LASTPIN (-8625 3625) $PN 2
J 0
(-8615 3605);
DISPLAY 0.489362 (-8615 3605);
FORCEPROP 1 LAST MATERIAL X6S
J 0
(-8575 3625);
DISPLAY 0.489362 (-8575 3625);
PAINT SKYBLUE (-8575 3625);
FORCEPROP 1 LAST TOLERANCE 20%
J 0
(-8575 3675);
DISPLAY 0.489362 (-8575 3675);
PAINT SKYBLUE (-8575 3675);
FORCEPROP 1 LAST VALUE 22UF
J 0
(-8575 3775);
DISPLAY 0.489362 (-8575 3775);
PAINT SKYBLUE (-8575 3775);
FORCEPROP 1 LAST VOLTAGE 4V
J 0
(-8575 3725);
DISPLAY 0.489362 (-8575 3725);
PAINT SKYBLUE (-8575 3725);
FORCEPROP 1 LAST PACK_TYPE C0402
J 0
(-8575 3525);
DISPLAY 0.489362 (-8575 3525);
PAINT SKYBLUE (-8575 3525);
FORCEPROP 2 LAST CDS_LIB pure_quanta
J 0
(-8625 3725);
PAINT MONO (-8625 3725);
DISPLAY INVISIBLE (-8625 3725);
FORCEPROP 1 LAST PATH I15
J 0
(-8575 3875);
DISPLAY 0.978723 (-8575 3875);
PAINT WHITE (-8575 3875);
DISPLAY INVISIBLE (-8575 3875);
FORCEPROP 1 LAST PART_NUMBER CH622KMEB02
J 0
(-8575 3575);
DISPLAY 0.489362 (-8575 3575);
PAINT SKYBLUE (-8575 3575);
DISPLAY INVISIBLE (-8575 3575);
FORCEADD UNIVERSAL_GND..1
(-500 2900);
FORCEPROP 3 LASTPIN (-500 2950) SIG_NAME GND\g
J 0
(-490 2960);
DISPLAY 0.659574 (-490 2960);
PAINT MONO (-490 2960);
DISPLAY INVISIBLE (-490 2960);
FORCEPROP 2 LAST CDS_LIB pure_quanta_power
J 0
(-500 2900);
PAINT MONO (-500 2900);
DISPLAY INVISIBLE (-500 2900);
FORCEPROP 1 LAST HDL_POWER GND
J 1
(-475 2825);
DISPLAY 0.872340 (-475 2825);
PAINT GREEN (-475 2825);
DISPLAY INVISIBLE (-475 2825);
FORCEPROP 1 LAST PATH I150
J 0
(-425 2900);
DISPLAY 0.872340 (-425 2900);
PAINT AQUA (-425 2900);
DISPLAY INVISIBLE (-425 2900);
FORCEADD Q_CAP..1
(-900 3275);
FORCEPROP 1 LAST LOCATION C2651
J 0
(-850 3375);
DISPLAY 0.489362 (-850 3375);
PAINT SKYBLUE (-850 3375);
FORCEPROP 2 LAST $SEC 1
J 0
(-850 3475);
DISPLAY 0.680851 (-850 3475);
PAINT MONO (-850 3475);
DISPLAY INVISIBLE (-850 3475);
FORCEPROP 2 LAST CDS_SEC 1
J 0
(-850 3475);
DISPLAY 1.021277 (-850 3475);
DISPLAY INVISIBLE (-850 3475);
FORCEPROP 1 LASTPIN (-900 3375) $PN 1
J 0
(-890 3355);
DISPLAY 0.489362 (-890 3355);
FORCEPROP 1 LASTPIN (-900 3175) $PN 2
J 0
(-890 3155);
DISPLAY 0.489362 (-890 3155);
FORCEPROP 1 LAST MATERIAL X6S
J 0
(-850 3175);
DISPLAY 0.489362 (-850 3175);
PAINT SKYBLUE (-850 3175);
FORCEPROP 1 LAST TOLERANCE 20%
J 0
(-850 3225);
DISPLAY 0.489362 (-850 3225);
PAINT SKYBLUE (-850 3225);
FORCEPROP 1 LAST VALUE 22UF
J 0
(-850 3325);
DISPLAY 0.489362 (-850 3325);
PAINT SKYBLUE (-850 3325);
FORCEPROP 1 LAST VOLTAGE 4V
J 0
(-850 3275);
DISPLAY 0.489362 (-850 3275);
PAINT SKYBLUE (-850 3275);
FORCEPROP 1 LAST PACK_TYPE C0402
J 0
(-850 3075);
DISPLAY 0.489362 (-850 3075);
PAINT SKYBLUE (-850 3075);
FORCEPROP 2 LAST CDS_LIB pure_quanta
J 0
(-900 3275);
PAINT MONO (-900 3275);
DISPLAY INVISIBLE (-900 3275);
FORCEPROP 1 LAST PATH I151
J 0
(-850 3425);
DISPLAY 0.978723 (-850 3425);
PAINT WHITE (-850 3425);
DISPLAY INVISIBLE (-850 3425);
FORCEPROP 1 LAST PART_NUMBER CH622KMEB02
J 0
(-850 3125);
DISPLAY 0.489362 (-850 3125);
PAINT SKYBLUE (-850 3125);
DISPLAY INVISIBLE (-850 3125);
FORCEADD Q_CAP..1
(-500 3275);
FORCEPROP 1 LAST LOCATION C2656
J 0
(-450 3375);
DISPLAY 0.489362 (-450 3375);
PAINT SKYBLUE (-450 3375);
FORCEPROP 2 LAST $SEC 1
J 0
(-450 3475);
DISPLAY 0.680851 (-450 3475);
PAINT MONO (-450 3475);
DISPLAY INVISIBLE (-450 3475);
FORCEPROP 2 LAST CDS_SEC 1
J 0
(-450 3475);
DISPLAY 1.021277 (-450 3475);
DISPLAY INVISIBLE (-450 3475);
FORCEPROP 1 LASTPIN (-500 3375) $PN 1
J 0
(-490 3355);
DISPLAY 0.489362 (-490 3355);
FORCEPROP 1 LASTPIN (-500 3175) $PN 2
J 0
(-490 3155);
DISPLAY 0.489362 (-490 3155);
FORCEPROP 1 LAST MATERIAL X6S
J 0
(-450 3175);
DISPLAY 0.489362 (-450 3175);
PAINT SKYBLUE (-450 3175);
FORCEPROP 1 LAST TOLERANCE 20%
J 0
(-450 3225);
DISPLAY 0.489362 (-450 3225);
PAINT SKYBLUE (-450 3225);
FORCEPROP 1 LAST VALUE 22UF
J 0
(-450 3325);
DISPLAY 0.489362 (-450 3325);
PAINT SKYBLUE (-450 3325);
FORCEPROP 1 LAST VOLTAGE 4V
J 0
(-450 3275);
DISPLAY 0.489362 (-450 3275);
PAINT SKYBLUE (-450 3275);
FORCEPROP 1 LAST PACK_TYPE C0402
J 0
(-450 3075);
DISPLAY 0.489362 (-450 3075);
PAINT SKYBLUE (-450 3075);
FORCEPROP 2 LAST CDS_LIB pure_quanta
J 0
(-500 3275);
PAINT MONO (-500 3275);
DISPLAY INVISIBLE (-500 3275);
FORCEPROP 1 LAST PATH I152
J 0
(-450 3425);
DISPLAY 0.978723 (-450 3425);
PAINT WHITE (-450 3425);
DISPLAY INVISIBLE (-450 3425);
FORCEPROP 1 LAST PART_NUMBER CH622KMEB02
J 0
(-450 3125);
DISPLAY 0.489362 (-450 3125);
PAINT SKYBLUE (-450 3125);
DISPLAY INVISIBLE (-450 3125);
FORCEADD Q_CAP..1
(-4050 4325);
FORCEPROP 1 LAST LOCATION C2606
J 0
(-4000 4425);
DISPLAY 0.489362 (-4000 4425);
PAINT SKYBLUE (-4000 4425);
FORCEPROP 2 LAST $SEC 1
J 0
(-4000 4525);
DISPLAY 0.680851 (-4000 4525);
PAINT MONO (-4000 4525);
DISPLAY INVISIBLE (-4000 4525);
FORCEPROP 2 LAST CDS_SEC 1
J 0
(-4000 4525);
DISPLAY 1.021277 (-4000 4525);
DISPLAY INVISIBLE (-4000 4525);
FORCEPROP 1 LASTPIN (-4050 4425) $PN 1
J 0
(-4040 4405);
DISPLAY 0.489362 (-4040 4405);
FORCEPROP 1 LASTPIN (-4050 4225) $PN 2
J 0
(-4040 4205);
DISPLAY 0.489362 (-4040 4205);
FORCEPROP 1 LAST MATERIAL X6S
J 0
(-4000 4225);
DISPLAY 0.489362 (-4000 4225);
PAINT SKYBLUE (-4000 4225);
FORCEPROP 1 LAST TOLERANCE 20%
J 0
(-4000 4275);
DISPLAY 0.489362 (-4000 4275);
PAINT SKYBLUE (-4000 4275);
FORCEPROP 1 LAST VALUE 22UF
J 0
(-4000 4375);
DISPLAY 0.489362 (-4000 4375);
PAINT SKYBLUE (-4000 4375);
FORCEPROP 1 LAST VOLTAGE 4V
J 0
(-4000 4325);
DISPLAY 0.489362 (-4000 4325);
PAINT SKYBLUE (-4000 4325);
FORCEPROP 1 LAST PACK_TYPE C0402
J 0
(-4000 4125);
DISPLAY 0.489362 (-4000 4125);
PAINT SKYBLUE (-4000 4125);
FORCEPROP 2 LAST CDS_LIB pure_quanta
J 0
(-4050 4325);
PAINT MONO (-4050 4325);
DISPLAY INVISIBLE (-4050 4325);
FORCEPROP 1 LAST PATH I153
J 0
(-4000 4475);
DISPLAY 0.978723 (-4000 4475);
PAINT WHITE (-4000 4475);
DISPLAY INVISIBLE (-4000 4475);
FORCEPROP 1 LAST PART_NUMBER CH622KMEB02
J 0
(-4000 4175);
DISPLAY 0.489362 (-4000 4175);
PAINT SKYBLUE (-4000 4175);
DISPLAY INVISIBLE (-4000 4175);
FORCEADD Q_CAP..1
(-4075 5100);
FORCEPROP 1 LAST LOCATION C2605
J 0
(-4025 5200);
DISPLAY 0.489362 (-4025 5200);
PAINT SKYBLUE (-4025 5200);
FORCEPROP 2 LAST $SEC 1
J 0
(-4025 5300);
DISPLAY 0.680851 (-4025 5300);
PAINT MONO (-4025 5300);
DISPLAY INVISIBLE (-4025 5300);
FORCEPROP 2 LAST CDS_SEC 1
J 0
(-4025 5300);
DISPLAY 1.021277 (-4025 5300);
DISPLAY INVISIBLE (-4025 5300);
FORCEPROP 1 LASTPIN (-4075 5200) $PN 1
J 0
(-4065 5180);
DISPLAY 0.489362 (-4065 5180);
FORCEPROP 1 LASTPIN (-4075 5000) $PN 2
J 0
(-4065 4980);
DISPLAY 0.489362 (-4065 4980);
FORCEPROP 1 LAST MATERIAL X6S
J 0
(-4025 5000);
DISPLAY 0.489362 (-4025 5000);
PAINT SKYBLUE (-4025 5000);
FORCEPROP 1 LAST TOLERANCE 20%
J 0
(-4025 5050);
DISPLAY 0.489362 (-4025 5050);
PAINT SKYBLUE (-4025 5050);
FORCEPROP 1 LAST VALUE 22UF
J 0
(-4025 5150);
DISPLAY 0.489362 (-4025 5150);
PAINT SKYBLUE (-4025 5150);
FORCEPROP 1 LAST VOLTAGE 4V
J 0
(-4025 5100);
DISPLAY 0.489362 (-4025 5100);
PAINT SKYBLUE (-4025 5100);
FORCEPROP 1 LAST PACK_TYPE C0402
J 0
(-4025 4900);
DISPLAY 0.489362 (-4025 4900);
PAINT SKYBLUE (-4025 4900);
FORCEPROP 2 LAST CDS_LIB pure_quanta
J 0
(-4075 5100);
PAINT MONO (-4075 5100);
DISPLAY INVISIBLE (-4075 5100);
FORCEPROP 1 LAST PATH I154
J 0
(-4025 5250);
DISPLAY 0.978723 (-4025 5250);
PAINT WHITE (-4025 5250);
DISPLAY INVISIBLE (-4025 5250);
FORCEPROP 1 LAST PART_NUMBER CH622KMEB02
J 0
(-4025 4950);
DISPLAY 0.489362 (-4025 4950);
PAINT SKYBLUE (-4025 4950);
DISPLAY INVISIBLE (-4025 4950);
FORCEADD Q_CAP..1
(-3600 4325);
FORCEPROP 1 LAST LOCATION C2613
J 0
(-3550 4425);
DISPLAY 0.489362 (-3550 4425);
PAINT SKYBLUE (-3550 4425);
FORCEPROP 2 LAST $SEC 1
J 0
(-3550 4525);
DISPLAY 0.680851 (-3550 4525);
PAINT MONO (-3550 4525);
DISPLAY INVISIBLE (-3550 4525);
FORCEPROP 2 LAST CDS_SEC 1
J 0
(-3550 4525);
DISPLAY 1.021277 (-3550 4525);
DISPLAY INVISIBLE (-3550 4525);
FORCEPROP 1 LASTPIN (-3600 4425) $PN 1
J 0
(-3590 4405);
DISPLAY 0.489362 (-3590 4405);
FORCEPROP 1 LASTPIN (-3600 4225) $PN 2
J 0
(-3590 4205);
DISPLAY 0.489362 (-3590 4205);
FORCEPROP 1 LAST MATERIAL X6S
J 0
(-3550 4225);
DISPLAY 0.489362 (-3550 4225);
PAINT SKYBLUE (-3550 4225);
FORCEPROP 1 LAST TOLERANCE 20%
J 0
(-3550 4275);
DISPLAY 0.489362 (-3550 4275);
PAINT SKYBLUE (-3550 4275);
FORCEPROP 1 LAST VALUE 22UF
J 0
(-3550 4375);
DISPLAY 0.489362 (-3550 4375);
PAINT SKYBLUE (-3550 4375);
FORCEPROP 1 LAST VOLTAGE 4V
J 0
(-3550 4325);
DISPLAY 0.489362 (-3550 4325);
PAINT SKYBLUE (-3550 4325);
FORCEPROP 1 LAST PACK_TYPE C0402
J 0
(-3550 4125);
DISPLAY 0.489362 (-3550 4125);
PAINT SKYBLUE (-3550 4125);
FORCEPROP 2 LAST CDS_LIB pure_quanta
J 0
(-3600 4325);
PAINT MONO (-3600 4325);
DISPLAY INVISIBLE (-3600 4325);
FORCEPROP 1 LAST PATH I155
J 0
(-3550 4475);
DISPLAY 0.978723 (-3550 4475);
PAINT WHITE (-3550 4475);
DISPLAY INVISIBLE (-3550 4475);
FORCEPROP 1 LAST PART_NUMBER CH622KMEB02
J 0
(-3550 4175);
DISPLAY 0.489362 (-3550 4175);
PAINT SKYBLUE (-3550 4175);
DISPLAY INVISIBLE (-3550 4175);
FORCEADD Q_CAP..1
(-3625 5100);
FORCEPROP 1 LAST LOCATION C2612
J 0
(-3575 5200);
DISPLAY 0.489362 (-3575 5200);
PAINT SKYBLUE (-3575 5200);
FORCEPROP 2 LAST $SEC 1
J 0
(-3575 5300);
DISPLAY 0.680851 (-3575 5300);
PAINT MONO (-3575 5300);
DISPLAY INVISIBLE (-3575 5300);
FORCEPROP 2 LAST CDS_SEC 1
J 0
(-3575 5300);
DISPLAY 1.021277 (-3575 5300);
DISPLAY INVISIBLE (-3575 5300);
FORCEPROP 1 LASTPIN (-3625 5200) $PN 1
J 0
(-3615 5180);
DISPLAY 0.489362 (-3615 5180);
FORCEPROP 1 LASTPIN (-3625 5000) $PN 2
J 0
(-3615 4980);
DISPLAY 0.489362 (-3615 4980);
FORCEPROP 1 LAST MATERIAL X6S
J 0
(-3575 5000);
DISPLAY 0.489362 (-3575 5000);
PAINT SKYBLUE (-3575 5000);
FORCEPROP 1 LAST TOLERANCE 20%
J 0
(-3575 5050);
DISPLAY 0.489362 (-3575 5050);
PAINT SKYBLUE (-3575 5050);
FORCEPROP 1 LAST VALUE 22UF
J 0
(-3575 5150);
DISPLAY 0.489362 (-3575 5150);
PAINT SKYBLUE (-3575 5150);
FORCEPROP 1 LAST VOLTAGE 4V
J 0
(-3575 5100);
DISPLAY 0.489362 (-3575 5100);
PAINT SKYBLUE (-3575 5100);
FORCEPROP 1 LAST PACK_TYPE C0402
J 0
(-3575 4900);
DISPLAY 0.489362 (-3575 4900);
PAINT SKYBLUE (-3575 4900);
FORCEPROP 2 LAST CDS_LIB pure_quanta
J 0
(-3625 5100);
PAINT MONO (-3625 5100);
DISPLAY INVISIBLE (-3625 5100);
FORCEPROP 1 LAST PATH I156
J 0
(-3575 5250);
DISPLAY 0.978723 (-3575 5250);
PAINT WHITE (-3575 5250);
DISPLAY INVISIBLE (-3575 5250);
FORCEPROP 1 LAST PART_NUMBER CH622KMEB02
J 0
(-3575 4950);
DISPLAY 0.489362 (-3575 4950);
PAINT SKYBLUE (-3575 4950);
DISPLAY INVISIBLE (-3575 4950);
FORCEADD Q_CAP..1
(-3175 5100);
FORCEPROP 1 LAST LOCATION C2619
J 0
(-3125 5200);
DISPLAY 0.489362 (-3125 5200);
PAINT SKYBLUE (-3125 5200);
FORCEPROP 2 LAST $SEC 1
J 0
(-3125 5300);
DISPLAY 0.680851 (-3125 5300);
PAINT MONO (-3125 5300);
DISPLAY INVISIBLE (-3125 5300);
FORCEPROP 2 LAST CDS_SEC 1
J 0
(-3125 5300);
DISPLAY 1.021277 (-3125 5300);
DISPLAY INVISIBLE (-3125 5300);
FORCEPROP 1 LASTPIN (-3175 5200) $PN 1
J 0
(-3165 5180);
DISPLAY 0.489362 (-3165 5180);
FORCEPROP 1 LASTPIN (-3175 5000) $PN 2
J 0
(-3165 4980);
DISPLAY 0.489362 (-3165 4980);
FORCEPROP 1 LAST MATERIAL X6S
J 0
(-3125 5000);
DISPLAY 0.489362 (-3125 5000);
PAINT SKYBLUE (-3125 5000);
FORCEPROP 1 LAST TOLERANCE 20%
J 0
(-3125 5050);
DISPLAY 0.489362 (-3125 5050);
PAINT SKYBLUE (-3125 5050);
FORCEPROP 1 LAST VALUE 22UF
J 0
(-3125 5150);
DISPLAY 0.489362 (-3125 5150);
PAINT SKYBLUE (-3125 5150);
FORCEPROP 1 LAST VOLTAGE 4V
J 0
(-3125 5100);
DISPLAY 0.489362 (-3125 5100);
PAINT SKYBLUE (-3125 5100);
FORCEPROP 1 LAST PACK_TYPE C0402
J 0
(-3125 4900);
DISPLAY 0.489362 (-3125 4900);
PAINT SKYBLUE (-3125 4900);
FORCEPROP 2 LAST CDS_LIB pure_quanta
J 0
(-3175 5100);
PAINT MONO (-3175 5100);
DISPLAY INVISIBLE (-3175 5100);
FORCEPROP 1 LAST PATH I157
J 0
(-3125 5250);
DISPLAY 0.978723 (-3125 5250);
PAINT WHITE (-3125 5250);
DISPLAY INVISIBLE (-3125 5250);
FORCEPROP 1 LAST PART_NUMBER CH622KMEB02
J 0
(-3125 4950);
DISPLAY 0.489362 (-3125 4950);
PAINT SKYBLUE (-3125 4950);
DISPLAY INVISIBLE (-3125 4950);
FORCEADD Q_CAP..1
(-4075 5900);
FORCEPROP 1 LAST LOCATION C2604
J 0
(-4025 6000);
DISPLAY 0.489362 (-4025 6000);
PAINT SKYBLUE (-4025 6000);
FORCEPROP 2 LAST $SEC 1
J 0
(-4025 6100);
DISPLAY 0.680851 (-4025 6100);
PAINT MONO (-4025 6100);
DISPLAY INVISIBLE (-4025 6100);
FORCEPROP 2 LAST CDS_SEC 1
J 0
(-4025 6100);
DISPLAY 1.021277 (-4025 6100);
DISPLAY INVISIBLE (-4025 6100);
FORCEPROP 1 LASTPIN (-4075 6000) $PN 1
J 0
(-4065 5980);
DISPLAY 0.489362 (-4065 5980);
FORCEPROP 1 LASTPIN (-4075 5800) $PN 2
J 0
(-4065 5780);
DISPLAY 0.489362 (-4065 5780);
FORCEPROP 1 LAST MATERIAL X6S
J 0
(-4025 5800);
DISPLAY 0.489362 (-4025 5800);
PAINT SKYBLUE (-4025 5800);
FORCEPROP 1 LAST TOLERANCE 20%
J 0
(-4025 5850);
DISPLAY 0.489362 (-4025 5850);
PAINT SKYBLUE (-4025 5850);
FORCEPROP 1 LAST VALUE 22UF
J 0
(-4025 5950);
DISPLAY 0.489362 (-4025 5950);
PAINT SKYBLUE (-4025 5950);
FORCEPROP 1 LAST VOLTAGE 4V
J 0
(-4025 5900);
DISPLAY 0.489362 (-4025 5900);
PAINT SKYBLUE (-4025 5900);
FORCEPROP 1 LAST PACK_TYPE C0402
J 0
(-4025 5700);
DISPLAY 0.489362 (-4025 5700);
PAINT SKYBLUE (-4025 5700);
FORCEPROP 2 LAST CDS_LIB pure_quanta
J 0
(-4075 5900);
PAINT MONO (-4075 5900);
DISPLAY INVISIBLE (-4075 5900);
FORCEPROP 1 LAST PATH I158
J 0
(-4025 6050);
DISPLAY 0.978723 (-4025 6050);
PAINT WHITE (-4025 6050);
DISPLAY INVISIBLE (-4025 6050);
FORCEPROP 1 LAST PART_NUMBER CH622KMEB02
J 0
(-4025 5750);
DISPLAY 0.489362 (-4025 5750);
PAINT SKYBLUE (-4025 5750);
DISPLAY INVISIBLE (-4025 5750);
FORCEADD Q_CAP..1
(-3625 5900);
FORCEPROP 1 LAST LOCATION C2611
J 0
(-3575 6000);
DISPLAY 0.489362 (-3575 6000);
PAINT SKYBLUE (-3575 6000);
FORCEPROP 2 LAST $SEC 1
J 0
(-3575 6100);
DISPLAY 0.680851 (-3575 6100);
PAINT MONO (-3575 6100);
DISPLAY INVISIBLE (-3575 6100);
FORCEPROP 2 LAST CDS_SEC 1
J 0
(-3575 6100);
DISPLAY 1.021277 (-3575 6100);
DISPLAY INVISIBLE (-3575 6100);
FORCEPROP 1 LASTPIN (-3625 6000) $PN 1
J 0
(-3615 5980);
DISPLAY 0.489362 (-3615 5980);
FORCEPROP 1 LASTPIN (-3625 5800) $PN 2
J 0
(-3615 5780);
DISPLAY 0.489362 (-3615 5780);
FORCEPROP 1 LAST MATERIAL X6S
J 0
(-3575 5800);
DISPLAY 0.489362 (-3575 5800);
PAINT SKYBLUE (-3575 5800);
FORCEPROP 1 LAST TOLERANCE 20%
J 0
(-3575 5850);
DISPLAY 0.489362 (-3575 5850);
PAINT SKYBLUE (-3575 5850);
FORCEPROP 1 LAST VALUE 22UF
J 0
(-3575 5950);
DISPLAY 0.489362 (-3575 5950);
PAINT SKYBLUE (-3575 5950);
FORCEPROP 1 LAST VOLTAGE 4V
J 0
(-3575 5900);
DISPLAY 0.489362 (-3575 5900);
PAINT SKYBLUE (-3575 5900);
FORCEPROP 1 LAST PACK_TYPE C0402
J 0
(-3575 5700);
DISPLAY 0.489362 (-3575 5700);
PAINT SKYBLUE (-3575 5700);
FORCEPROP 2 LAST CDS_LIB pure_quanta
J 0
(-3625 5900);
PAINT MONO (-3625 5900);
DISPLAY INVISIBLE (-3625 5900);
FORCEPROP 1 LAST PATH I159
J 0
(-3575 6050);
DISPLAY 0.978723 (-3575 6050);
PAINT WHITE (-3575 6050);
DISPLAY INVISIBLE (-3575 6050);
FORCEPROP 1 LAST PART_NUMBER CH622KMEB02
J 0
(-3575 5750);
DISPLAY 0.489362 (-3575 5750);
PAINT SKYBLUE (-3575 5750);
DISPLAY INVISIBLE (-3575 5750);
FORCEADD Q_CAP..1
(-9100 4425);
FORCEPROP 1 LAST LOCATION C2529
J 0
(-9050 4525);
DISPLAY 0.489362 (-9050 4525);
PAINT SKYBLUE (-9050 4525);
FORCEPROP 2 LAST $SEC 1
J 0
(-9050 4625);
DISPLAY 0.680851 (-9050 4625);
PAINT MONO (-9050 4625);
DISPLAY INVISIBLE (-9050 4625);
FORCEPROP 2 LAST CDS_SEC 1
J 0
(-9050 4625);
DISPLAY 1.021277 (-9050 4625);
DISPLAY INVISIBLE (-9050 4625);
FORCEPROP 1 LASTPIN (-9100 4525) $PN 1
J 0
(-9090 4505);
DISPLAY 0.489362 (-9090 4505);
FORCEPROP 1 LASTPIN (-9100 4325) $PN 2
J 0
(-9090 4305);
DISPLAY 0.489362 (-9090 4305);
FORCEPROP 1 LAST MATERIAL X6S
J 0
(-9050 4325);
DISPLAY 0.489362 (-9050 4325);
PAINT SKYBLUE (-9050 4325);
FORCEPROP 1 LAST TOLERANCE 20%
J 0
(-9050 4375);
DISPLAY 0.489362 (-9050 4375);
PAINT SKYBLUE (-9050 4375);
FORCEPROP 1 LAST VALUE 22UF
J 0
(-9050 4475);
DISPLAY 0.489362 (-9050 4475);
PAINT SKYBLUE (-9050 4475);
FORCEPROP 1 LAST VOLTAGE 4V
J 0
(-9050 4425);
DISPLAY 0.489362 (-9050 4425);
PAINT SKYBLUE (-9050 4425);
FORCEPROP 1 LAST PACK_TYPE C0402
J 0
(-9050 4225);
DISPLAY 0.489362 (-9050 4225);
PAINT SKYBLUE (-9050 4225);
FORCEPROP 2 LAST CDS_LIB pure_quanta
J 0
(-9100 4425);
PAINT MONO (-9100 4425);
DISPLAY INVISIBLE (-9100 4425);
FORCEPROP 1 LAST PATH I16
J 0
(-9050 4575);
DISPLAY 0.978723 (-9050 4575);
PAINT WHITE (-9050 4575);
DISPLAY INVISIBLE (-9050 4575);
FORCEPROP 1 LAST PART_NUMBER CH622KMEB02
J 0
(-9050 4275);
DISPLAY 0.489362 (-9050 4275);
PAINT SKYBLUE (-9050 4275);
DISPLAY INVISIBLE (-9050 4275);
FORCEADD Q_CAP..1
(-3175 5900);
FORCEPROP 1 LAST LOCATION C2618
J 0
(-3125 6000);
DISPLAY 0.489362 (-3125 6000);
PAINT SKYBLUE (-3125 6000);
FORCEPROP 2 LAST $SEC 1
J 0
(-3125 6100);
DISPLAY 0.680851 (-3125 6100);
PAINT MONO (-3125 6100);
DISPLAY INVISIBLE (-3125 6100);
FORCEPROP 2 LAST CDS_SEC 1
J 0
(-3125 6100);
DISPLAY 1.021277 (-3125 6100);
DISPLAY INVISIBLE (-3125 6100);
FORCEPROP 1 LASTPIN (-3175 6000) $PN 1
J 0
(-3165 5980);
DISPLAY 0.489362 (-3165 5980);
FORCEPROP 1 LASTPIN (-3175 5800) $PN 2
J 0
(-3165 5780);
DISPLAY 0.489362 (-3165 5780);
FORCEPROP 1 LAST MATERIAL X6S
J 0
(-3125 5800);
DISPLAY 0.489362 (-3125 5800);
PAINT SKYBLUE (-3125 5800);
FORCEPROP 1 LAST TOLERANCE 20%
J 0
(-3125 5850);
DISPLAY 0.489362 (-3125 5850);
PAINT SKYBLUE (-3125 5850);
FORCEPROP 1 LAST VALUE 22UF
J 0
(-3125 5950);
DISPLAY 0.489362 (-3125 5950);
PAINT SKYBLUE (-3125 5950);
FORCEPROP 1 LAST VOLTAGE 4V
J 0
(-3125 5900);
DISPLAY 0.489362 (-3125 5900);
PAINT SKYBLUE (-3125 5900);
FORCEPROP 1 LAST PACK_TYPE C0402
J 0
(-3125 5700);
DISPLAY 0.489362 (-3125 5700);
PAINT SKYBLUE (-3125 5700);
FORCEPROP 2 LAST CDS_LIB pure_quanta
J 0
(-3175 5900);
PAINT MONO (-3175 5900);
DISPLAY INVISIBLE (-3175 5900);
FORCEPROP 1 LAST PATH I160
J 0
(-3125 6050);
DISPLAY 0.978723 (-3125 6050);
PAINT WHITE (-3125 6050);
DISPLAY INVISIBLE (-3125 6050);
FORCEPROP 1 LAST PART_NUMBER CH622KMEB02
J 0
(-3125 5750);
DISPLAY 0.489362 (-3125 5750);
PAINT SKYBLUE (-3125 5750);
DISPLAY INVISIBLE (-3125 5750);
FORCEADD Q_CAP..1
(-3150 4325);
FORCEPROP 1 LAST LOCATION C2620
J 0
(-3100 4425);
DISPLAY 0.489362 (-3100 4425);
PAINT SKYBLUE (-3100 4425);
FORCEPROP 2 LAST $SEC 1
J 0
(-3100 4525);
DISPLAY 0.680851 (-3100 4525);
PAINT MONO (-3100 4525);
DISPLAY INVISIBLE (-3100 4525);
FORCEPROP 2 LAST CDS_SEC 1
J 0
(-3100 4525);
DISPLAY 1.021277 (-3100 4525);
DISPLAY INVISIBLE (-3100 4525);
FORCEPROP 1 LASTPIN (-3150 4425) $PN 1
J 0
(-3140 4405);
DISPLAY 0.489362 (-3140 4405);
FORCEPROP 1 LASTPIN (-3150 4225) $PN 2
J 0
(-3140 4205);
DISPLAY 0.489362 (-3140 4205);
FORCEPROP 1 LAST MATERIAL X6S
J 0
(-3100 4225);
DISPLAY 0.489362 (-3100 4225);
PAINT SKYBLUE (-3100 4225);
FORCEPROP 1 LAST TOLERANCE 20%
J 0
(-3100 4275);
DISPLAY 0.489362 (-3100 4275);
PAINT SKYBLUE (-3100 4275);
FORCEPROP 1 LAST VALUE 22UF
J 0
(-3100 4375);
DISPLAY 0.489362 (-3100 4375);
PAINT SKYBLUE (-3100 4375);
FORCEPROP 1 LAST VOLTAGE 4V
J 0
(-3100 4325);
DISPLAY 0.489362 (-3100 4325);
PAINT SKYBLUE (-3100 4325);
FORCEPROP 1 LAST PACK_TYPE C0402
J 0
(-3100 4125);
DISPLAY 0.489362 (-3100 4125);
PAINT SKYBLUE (-3100 4125);
FORCEPROP 2 LAST CDS_LIB pure_quanta
J 0
(-3150 4325);
PAINT MONO (-3150 4325);
DISPLAY INVISIBLE (-3150 4325);
FORCEPROP 1 LAST PATH I161
J 0
(-3100 4475);
DISPLAY 0.978723 (-3100 4475);
PAINT WHITE (-3100 4475);
DISPLAY INVISIBLE (-3100 4475);
FORCEPROP 1 LAST PART_NUMBER CH622KMEB02
J 0
(-3100 4175);
DISPLAY 0.489362 (-3100 4175);
PAINT SKYBLUE (-3100 4175);
DISPLAY INVISIBLE (-3100 4175);
FORCEADD Q_CAP..1
(-2725 5100);
FORCEPROP 1 LAST LOCATION C2626
J 0
(-2675 5200);
DISPLAY 0.489362 (-2675 5200);
PAINT SKYBLUE (-2675 5200);
FORCEPROP 2 LAST $SEC 1
J 0
(-2675 5300);
DISPLAY 0.680851 (-2675 5300);
PAINT MONO (-2675 5300);
DISPLAY INVISIBLE (-2675 5300);
FORCEPROP 2 LAST CDS_SEC 1
J 0
(-2675 5300);
DISPLAY 1.021277 (-2675 5300);
DISPLAY INVISIBLE (-2675 5300);
FORCEPROP 1 LASTPIN (-2725 5200) $PN 1
J 0
(-2715 5180);
DISPLAY 0.489362 (-2715 5180);
FORCEPROP 1 LASTPIN (-2725 5000) $PN 2
J 0
(-2715 4980);
DISPLAY 0.489362 (-2715 4980);
FORCEPROP 1 LAST MATERIAL X6S
J 0
(-2675 5000);
DISPLAY 0.489362 (-2675 5000);
PAINT SKYBLUE (-2675 5000);
FORCEPROP 1 LAST TOLERANCE 20%
J 0
(-2675 5050);
DISPLAY 0.489362 (-2675 5050);
PAINT SKYBLUE (-2675 5050);
FORCEPROP 1 LAST VALUE 22UF
J 0
(-2675 5150);
DISPLAY 0.489362 (-2675 5150);
PAINT SKYBLUE (-2675 5150);
FORCEPROP 1 LAST VOLTAGE 4V
J 0
(-2675 5100);
DISPLAY 0.489362 (-2675 5100);
PAINT SKYBLUE (-2675 5100);
FORCEPROP 1 LAST PACK_TYPE C0402
J 0
(-2675 4900);
DISPLAY 0.489362 (-2675 4900);
PAINT SKYBLUE (-2675 4900);
FORCEPROP 2 LAST CDS_LIB pure_quanta
J 0
(-2725 5100);
PAINT MONO (-2725 5100);
DISPLAY INVISIBLE (-2725 5100);
FORCEPROP 1 LAST PATH I162
J 0
(-2675 5250);
DISPLAY 0.978723 (-2675 5250);
PAINT WHITE (-2675 5250);
DISPLAY INVISIBLE (-2675 5250);
FORCEPROP 1 LAST PART_NUMBER CH622KMEB02
J 0
(-2675 4950);
DISPLAY 0.489362 (-2675 4950);
PAINT SKYBLUE (-2675 4950);
DISPLAY INVISIBLE (-2675 4950);
FORCEADD Q_CAP..1
(-2275 5100);
FORCEPROP 1 LAST LOCATION C2632
J 0
(-2225 5200);
DISPLAY 0.489362 (-2225 5200);
PAINT SKYBLUE (-2225 5200);
FORCEPROP 2 LAST $SEC 1
J 0
(-2225 5300);
DISPLAY 0.680851 (-2225 5300);
PAINT MONO (-2225 5300);
DISPLAY INVISIBLE (-2225 5300);
FORCEPROP 2 LAST CDS_SEC 1
J 0
(-2225 5300);
DISPLAY 1.021277 (-2225 5300);
DISPLAY INVISIBLE (-2225 5300);
FORCEPROP 1 LASTPIN (-2275 5200) $PN 1
J 0
(-2265 5180);
DISPLAY 0.489362 (-2265 5180);
FORCEPROP 1 LASTPIN (-2275 5000) $PN 2
J 0
(-2265 4980);
DISPLAY 0.489362 (-2265 4980);
FORCEPROP 1 LAST MATERIAL X6S
J 0
(-2225 5000);
DISPLAY 0.489362 (-2225 5000);
PAINT SKYBLUE (-2225 5000);
FORCEPROP 1 LAST TOLERANCE 20%
J 0
(-2225 5050);
DISPLAY 0.489362 (-2225 5050);
PAINT SKYBLUE (-2225 5050);
FORCEPROP 1 LAST VALUE 22UF
J 0
(-2225 5150);
DISPLAY 0.489362 (-2225 5150);
PAINT SKYBLUE (-2225 5150);
FORCEPROP 1 LAST VOLTAGE 4V
J 0
(-2225 5100);
DISPLAY 0.489362 (-2225 5100);
PAINT SKYBLUE (-2225 5100);
FORCEPROP 1 LAST PACK_TYPE C0402
J 0
(-2225 4900);
DISPLAY 0.489362 (-2225 4900);
PAINT SKYBLUE (-2225 4900);
FORCEPROP 2 LAST CDS_LIB pure_quanta
J 0
(-2275 5100);
PAINT MONO (-2275 5100);
DISPLAY INVISIBLE (-2275 5100);
FORCEPROP 1 LAST PATH I163
J 0
(-2225 5250);
DISPLAY 0.978723 (-2225 5250);
PAINT WHITE (-2225 5250);
DISPLAY INVISIBLE (-2225 5250);
FORCEPROP 1 LAST PART_NUMBER CH622KMEB02
J 0
(-2225 4950);
DISPLAY 0.489362 (-2225 4950);
PAINT SKYBLUE (-2225 4950);
DISPLAY INVISIBLE (-2225 4950);
FORCEADD Q_CAP..1
(-2725 5900);
FORCEPROP 1 LAST LOCATION C2625
J 0
(-2675 6000);
DISPLAY 0.489362 (-2675 6000);
PAINT SKYBLUE (-2675 6000);
FORCEPROP 2 LAST $SEC 1
J 0
(-2675 6100);
DISPLAY 0.680851 (-2675 6100);
PAINT MONO (-2675 6100);
DISPLAY INVISIBLE (-2675 6100);
FORCEPROP 2 LAST CDS_SEC 1
J 0
(-2675 6100);
DISPLAY 1.021277 (-2675 6100);
DISPLAY INVISIBLE (-2675 6100);
FORCEPROP 1 LASTPIN (-2725 6000) $PN 1
J 0
(-2715 5980);
DISPLAY 0.489362 (-2715 5980);
FORCEPROP 1 LASTPIN (-2725 5800) $PN 2
J 0
(-2715 5780);
DISPLAY 0.489362 (-2715 5780);
FORCEPROP 1 LAST MATERIAL X6S
J 0
(-2675 5800);
DISPLAY 0.489362 (-2675 5800);
PAINT SKYBLUE (-2675 5800);
FORCEPROP 1 LAST TOLERANCE 20%
J 0
(-2675 5850);
DISPLAY 0.489362 (-2675 5850);
PAINT SKYBLUE (-2675 5850);
FORCEPROP 1 LAST VALUE 22UF
J 0
(-2675 5950);
DISPLAY 0.489362 (-2675 5950);
PAINT SKYBLUE (-2675 5950);
FORCEPROP 1 LAST VOLTAGE 4V
J 0
(-2675 5900);
DISPLAY 0.489362 (-2675 5900);
PAINT SKYBLUE (-2675 5900);
FORCEPROP 1 LAST PACK_TYPE C0402
J 0
(-2675 5700);
DISPLAY 0.489362 (-2675 5700);
PAINT SKYBLUE (-2675 5700);
FORCEPROP 2 LAST CDS_LIB pure_quanta
J 0
(-2725 5900);
PAINT MONO (-2725 5900);
DISPLAY INVISIBLE (-2725 5900);
FORCEPROP 1 LAST PATH I164
J 0
(-2675 6050);
DISPLAY 0.978723 (-2675 6050);
PAINT WHITE (-2675 6050);
DISPLAY INVISIBLE (-2675 6050);
FORCEPROP 1 LAST PART_NUMBER CH622KMEB02
J 0
(-2675 5750);
DISPLAY 0.489362 (-2675 5750);
PAINT SKYBLUE (-2675 5750);
DISPLAY INVISIBLE (-2675 5750);
FORCEADD Q_CAP..1
(-2275 5900);
FORCEPROP 1 LAST LOCATION C2631
J 0
(-2225 6000);
DISPLAY 0.489362 (-2225 6000);
PAINT SKYBLUE (-2225 6000);
FORCEPROP 2 LAST $SEC 1
J 0
(-2225 6100);
DISPLAY 0.680851 (-2225 6100);
PAINT MONO (-2225 6100);
DISPLAY INVISIBLE (-2225 6100);
FORCEPROP 2 LAST CDS_SEC 1
J 0
(-2225 6100);
DISPLAY 1.021277 (-2225 6100);
DISPLAY INVISIBLE (-2225 6100);
FORCEPROP 1 LASTPIN (-2275 6000) $PN 1
J 0
(-2265 5980);
DISPLAY 0.489362 (-2265 5980);
FORCEPROP 1 LASTPIN (-2275 5800) $PN 2
J 0
(-2265 5780);
DISPLAY 0.489362 (-2265 5780);
FORCEPROP 1 LAST MATERIAL X6S
J 0
(-2225 5800);
DISPLAY 0.489362 (-2225 5800);
PAINT SKYBLUE (-2225 5800);
FORCEPROP 1 LAST TOLERANCE 20%
J 0
(-2225 5850);
DISPLAY 0.489362 (-2225 5850);
PAINT SKYBLUE (-2225 5850);
FORCEPROP 1 LAST VALUE 22UF
J 0
(-2225 5950);
DISPLAY 0.489362 (-2225 5950);
PAINT SKYBLUE (-2225 5950);
FORCEPROP 1 LAST VOLTAGE 4V
J 0
(-2225 5900);
DISPLAY 0.489362 (-2225 5900);
PAINT SKYBLUE (-2225 5900);
FORCEPROP 1 LAST PACK_TYPE C0402
J 0
(-2225 5700);
DISPLAY 0.489362 (-2225 5700);
PAINT SKYBLUE (-2225 5700);
FORCEPROP 2 LAST CDS_LIB pure_quanta
J 0
(-2275 5900);
PAINT MONO (-2275 5900);
DISPLAY INVISIBLE (-2275 5900);
FORCEPROP 1 LAST PATH I165
J 0
(-2225 6050);
DISPLAY 0.978723 (-2225 6050);
PAINT WHITE (-2225 6050);
DISPLAY INVISIBLE (-2225 6050);
FORCEPROP 1 LAST PART_NUMBER CH622KMEB02
J 0
(-2225 5750);
DISPLAY 0.489362 (-2225 5750);
PAINT SKYBLUE (-2225 5750);
DISPLAY INVISIBLE (-2225 5750);
FORCEADD Q_CAP..1
(-1825 5100);
FORCEPROP 1 LAST LOCATION C2638
J 0
(-1775 5200);
DISPLAY 0.489362 (-1775 5200);
PAINT SKYBLUE (-1775 5200);
FORCEPROP 2 LAST $SEC 1
J 0
(-1775 5300);
DISPLAY 0.680851 (-1775 5300);
PAINT MONO (-1775 5300);
DISPLAY INVISIBLE (-1775 5300);
FORCEPROP 2 LAST CDS_SEC 1
J 0
(-1775 5300);
DISPLAY 1.021277 (-1775 5300);
DISPLAY INVISIBLE (-1775 5300);
FORCEPROP 1 LASTPIN (-1825 5200) $PN 1
J 0
(-1815 5180);
DISPLAY 0.489362 (-1815 5180);
FORCEPROP 1 LASTPIN (-1825 5000) $PN 2
J 0
(-1815 4980);
DISPLAY 0.489362 (-1815 4980);
FORCEPROP 1 LAST MATERIAL X6S
J 0
(-1775 5000);
DISPLAY 0.489362 (-1775 5000);
PAINT SKYBLUE (-1775 5000);
FORCEPROP 1 LAST TOLERANCE 20%
J 0
(-1775 5050);
DISPLAY 0.489362 (-1775 5050);
PAINT SKYBLUE (-1775 5050);
FORCEPROP 1 LAST VALUE 22UF
J 0
(-1775 5150);
DISPLAY 0.489362 (-1775 5150);
PAINT SKYBLUE (-1775 5150);
FORCEPROP 1 LAST VOLTAGE 4V
J 0
(-1775 5100);
DISPLAY 0.489362 (-1775 5100);
PAINT SKYBLUE (-1775 5100);
FORCEPROP 1 LAST PACK_TYPE C0402
J 0
(-1775 4900);
DISPLAY 0.489362 (-1775 4900);
PAINT SKYBLUE (-1775 4900);
FORCEPROP 2 LAST CDS_LIB pure_quanta
J 0
(-1825 5100);
PAINT MONO (-1825 5100);
DISPLAY INVISIBLE (-1825 5100);
FORCEPROP 1 LAST PATH I166
J 0
(-1775 5250);
DISPLAY 0.978723 (-1775 5250);
PAINT WHITE (-1775 5250);
DISPLAY INVISIBLE (-1775 5250);
FORCEPROP 1 LAST PART_NUMBER CH622KMEB02
J 0
(-1775 4950);
DISPLAY 0.489362 (-1775 4950);
PAINT SKYBLUE (-1775 4950);
DISPLAY INVISIBLE (-1775 4950);
FORCEADD Q_CAP..1
(-1375 5100);
FORCEPROP 1 LAST LOCATION C2644
J 0
(-1325 5200);
DISPLAY 0.489362 (-1325 5200);
PAINT SKYBLUE (-1325 5200);
FORCEPROP 2 LAST $SEC 1
J 0
(-1325 5300);
DISPLAY 0.680851 (-1325 5300);
PAINT MONO (-1325 5300);
DISPLAY INVISIBLE (-1325 5300);
FORCEPROP 2 LAST CDS_SEC 1
J 0
(-1325 5300);
DISPLAY 1.021277 (-1325 5300);
DISPLAY INVISIBLE (-1325 5300);
FORCEPROP 1 LASTPIN (-1375 5200) $PN 1
J 0
(-1365 5180);
DISPLAY 0.489362 (-1365 5180);
FORCEPROP 1 LASTPIN (-1375 5000) $PN 2
J 0
(-1365 4980);
DISPLAY 0.489362 (-1365 4980);
FORCEPROP 1 LAST MATERIAL X6S
J 0
(-1325 5000);
DISPLAY 0.489362 (-1325 5000);
PAINT SKYBLUE (-1325 5000);
FORCEPROP 1 LAST TOLERANCE 20%
J 0
(-1325 5050);
DISPLAY 0.489362 (-1325 5050);
PAINT SKYBLUE (-1325 5050);
FORCEPROP 1 LAST VALUE 22UF
J 0
(-1325 5150);
DISPLAY 0.489362 (-1325 5150);
PAINT SKYBLUE (-1325 5150);
FORCEPROP 1 LAST VOLTAGE 4V
J 0
(-1325 5100);
DISPLAY 0.489362 (-1325 5100);
PAINT SKYBLUE (-1325 5100);
FORCEPROP 1 LAST PACK_TYPE C0402
J 0
(-1325 4900);
DISPLAY 0.489362 (-1325 4900);
PAINT SKYBLUE (-1325 4900);
FORCEPROP 2 LAST CDS_LIB pure_quanta
J 0
(-1375 5100);
PAINT MONO (-1375 5100);
DISPLAY INVISIBLE (-1375 5100);
FORCEPROP 1 LAST PATH I167
J 0
(-1325 5250);
DISPLAY 0.978723 (-1325 5250);
PAINT WHITE (-1325 5250);
DISPLAY INVISIBLE (-1325 5250);
FORCEPROP 1 LAST PART_NUMBER CH622KMEB02
J 0
(-1325 4950);
DISPLAY 0.489362 (-1325 4950);
PAINT SKYBLUE (-1325 4950);
DISPLAY INVISIBLE (-1325 4950);
FORCEADD Q_CAP..1
(-1825 5900);
FORCEPROP 1 LAST LOCATION C2637
J 0
(-1775 6000);
DISPLAY 0.489362 (-1775 6000);
PAINT SKYBLUE (-1775 6000);
FORCEPROP 2 LAST $SEC 1
J 0
(-1775 6100);
DISPLAY 0.680851 (-1775 6100);
PAINT MONO (-1775 6100);
DISPLAY INVISIBLE (-1775 6100);
FORCEPROP 2 LAST CDS_SEC 1
J 0
(-1775 6100);
DISPLAY 1.021277 (-1775 6100);
DISPLAY INVISIBLE (-1775 6100);
FORCEPROP 1 LASTPIN (-1825 6000) $PN 1
J 0
(-1815 5980);
DISPLAY 0.489362 (-1815 5980);
FORCEPROP 1 LASTPIN (-1825 5800) $PN 2
J 0
(-1815 5780);
DISPLAY 0.489362 (-1815 5780);
FORCEPROP 1 LAST MATERIAL X6S
J 0
(-1775 5800);
DISPLAY 0.489362 (-1775 5800);
PAINT SKYBLUE (-1775 5800);
FORCEPROP 1 LAST TOLERANCE 20%
J 0
(-1775 5850);
DISPLAY 0.489362 (-1775 5850);
PAINT SKYBLUE (-1775 5850);
FORCEPROP 1 LAST VALUE 22UF
J 0
(-1775 5950);
DISPLAY 0.489362 (-1775 5950);
PAINT SKYBLUE (-1775 5950);
FORCEPROP 1 LAST VOLTAGE 4V
J 0
(-1775 5900);
DISPLAY 0.489362 (-1775 5900);
PAINT SKYBLUE (-1775 5900);
FORCEPROP 1 LAST PACK_TYPE C0402
J 0
(-1775 5700);
DISPLAY 0.489362 (-1775 5700);
PAINT SKYBLUE (-1775 5700);
FORCEPROP 2 LAST CDS_LIB pure_quanta
J 0
(-1825 5900);
PAINT MONO (-1825 5900);
DISPLAY INVISIBLE (-1825 5900);
FORCEPROP 1 LAST PATH I168
J 0
(-1775 6050);
DISPLAY 0.978723 (-1775 6050);
PAINT WHITE (-1775 6050);
DISPLAY INVISIBLE (-1775 6050);
FORCEPROP 1 LAST PART_NUMBER CH622KMEB02
J 0
(-1775 5750);
DISPLAY 0.489362 (-1775 5750);
PAINT SKYBLUE (-1775 5750);
DISPLAY INVISIBLE (-1775 5750);
FORCEADD Q_CAP..1
(-1375 5900);
FORCEPROP 1 LAST LOCATION C2643
J 0
(-1325 6000);
DISPLAY 0.489362 (-1325 6000);
PAINT SKYBLUE (-1325 6000);
FORCEPROP 2 LAST $SEC 1
J 0
(-1325 6100);
DISPLAY 0.680851 (-1325 6100);
PAINT MONO (-1325 6100);
DISPLAY INVISIBLE (-1325 6100);
FORCEPROP 2 LAST CDS_SEC 1
J 0
(-1325 6100);
DISPLAY 1.021277 (-1325 6100);
DISPLAY INVISIBLE (-1325 6100);
FORCEPROP 1 LASTPIN (-1375 6000) $PN 1
J 0
(-1365 5980);
DISPLAY 0.489362 (-1365 5980);
FORCEPROP 1 LASTPIN (-1375 5800) $PN 2
J 0
(-1365 5780);
DISPLAY 0.489362 (-1365 5780);
FORCEPROP 1 LAST MATERIAL X6S
J 0
(-1325 5800);
DISPLAY 0.489362 (-1325 5800);
PAINT SKYBLUE (-1325 5800);
FORCEPROP 1 LAST TOLERANCE 20%
J 0
(-1325 5850);
DISPLAY 0.489362 (-1325 5850);
PAINT SKYBLUE (-1325 5850);
FORCEPROP 1 LAST VALUE 22UF
J 0
(-1325 5950);
DISPLAY 0.489362 (-1325 5950);
PAINT SKYBLUE (-1325 5950);
FORCEPROP 1 LAST VOLTAGE 4V
J 0
(-1325 5900);
DISPLAY 0.489362 (-1325 5900);
PAINT SKYBLUE (-1325 5900);
FORCEPROP 1 LAST PACK_TYPE C0402
J 0
(-1325 5700);
DISPLAY 0.489362 (-1325 5700);
PAINT SKYBLUE (-1325 5700);
FORCEPROP 2 LAST CDS_LIB pure_quanta
J 0
(-1375 5900);
PAINT MONO (-1375 5900);
DISPLAY INVISIBLE (-1375 5900);
FORCEPROP 1 LAST PATH I169
J 0
(-1325 6050);
DISPLAY 0.978723 (-1325 6050);
PAINT WHITE (-1325 6050);
DISPLAY INVISIBLE (-1325 6050);
FORCEPROP 1 LAST PART_NUMBER CH622KMEB02
J 0
(-1325 5750);
DISPLAY 0.489362 (-1325 5750);
PAINT SKYBLUE (-1325 5750);
DISPLAY INVISIBLE (-1325 5750);
FORCEADD UNIVERSAL_POWER..1
(-9100 4700);
FORCEPROP 3 LASTPIN (-9100 4650) SIG_NAME PVDDCR_SOC_P0\g
J 0
(-9090 4660);
DISPLAY 0.659574 (-9090 4660);
PAINT MONO (-9090 4660);
DISPLAY INVISIBLE (-9090 4660);
FORCEPROP 1 LAST HDL_POWER PVDDCR_SOC_P0
J 1
(-9100 4750);
DISPLAY 0.489362 (-9100 4750);
PAINT GREEN (-9100 4750);
FORCEPROP 2 LAST CDS_LIB pure_quanta_power
J 0
(-9100 4700);
DISPLAY INVISIBLE (-9100 4700);
FORCEPROP 1 LAST PATH I17
J 0
(-9050 4725);
DISPLAY 0.872340 (-9050 4725);
PAINT AQUA (-9050 4725);
DISPLAY INVISIBLE (-9050 4725);
FORCEADD Q_CAP..1
(-925 5100);
FORCEPROP 1 LAST LOCATION C2650
J 0
(-875 5200);
DISPLAY 0.489362 (-875 5200);
PAINT SKYBLUE (-875 5200);
FORCEPROP 2 LAST $SEC 1
J 0
(-875 5300);
DISPLAY 0.680851 (-875 5300);
PAINT MONO (-875 5300);
DISPLAY INVISIBLE (-875 5300);
FORCEPROP 2 LAST CDS_SEC 1
J 0
(-875 5300);
DISPLAY 1.021277 (-875 5300);
DISPLAY INVISIBLE (-875 5300);
FORCEPROP 1 LASTPIN (-925 5200) $PN 1
J 0
(-915 5180);
DISPLAY 0.489362 (-915 5180);
FORCEPROP 1 LASTPIN (-925 5000) $PN 2
J 0
(-915 4980);
DISPLAY 0.489362 (-915 4980);
FORCEPROP 1 LAST MATERIAL X6S
J 0
(-875 5000);
DISPLAY 0.489362 (-875 5000);
PAINT SKYBLUE (-875 5000);
FORCEPROP 1 LAST TOLERANCE 20%
J 0
(-875 5050);
DISPLAY 0.489362 (-875 5050);
PAINT SKYBLUE (-875 5050);
FORCEPROP 1 LAST VALUE 22UF
J 0
(-875 5150);
DISPLAY 0.489362 (-875 5150);
PAINT SKYBLUE (-875 5150);
FORCEPROP 1 LAST VOLTAGE 4V
J 0
(-875 5100);
DISPLAY 0.489362 (-875 5100);
PAINT SKYBLUE (-875 5100);
FORCEPROP 1 LAST PACK_TYPE C0402
J 0
(-875 4900);
DISPLAY 0.489362 (-875 4900);
PAINT SKYBLUE (-875 4900);
FORCEPROP 2 LAST CDS_LIB pure_quanta
J 0
(-925 5100);
PAINT MONO (-925 5100);
DISPLAY INVISIBLE (-925 5100);
FORCEPROP 1 LAST PATH I170
J 0
(-875 5250);
DISPLAY 0.978723 (-875 5250);
PAINT WHITE (-875 5250);
DISPLAY INVISIBLE (-875 5250);
FORCEPROP 1 LAST PART_NUMBER CH622KMEB02
J 0
(-875 4950);
DISPLAY 0.489362 (-875 4950);
PAINT SKYBLUE (-875 4950);
DISPLAY INVISIBLE (-875 4950);
FORCEADD UNIVERSAL_GND..1
(-525 4725);
FORCEPROP 3 LASTPIN (-525 4775) SIG_NAME GND\g
J 0
(-515 4785);
DISPLAY 0.659574 (-515 4785);
PAINT MONO (-515 4785);
DISPLAY INVISIBLE (-515 4785);
FORCEPROP 2 LAST CDS_LIB pure_quanta_power
J 0
(-525 4725);
PAINT MONO (-525 4725);
DISPLAY INVISIBLE (-525 4725);
FORCEPROP 1 LAST HDL_POWER GND
J 1
(-500 4650);
DISPLAY 0.872340 (-500 4650);
PAINT GREEN (-500 4650);
DISPLAY INVISIBLE (-500 4650);
FORCEPROP 1 LAST PATH I171
J 0
(-450 4725);
DISPLAY 0.872340 (-450 4725);
PAINT AQUA (-450 4725);
DISPLAY INVISIBLE (-450 4725);
FORCEADD Q_CAP..1
(-525 5100);
FORCEPROP 1 LAST LOCATION C2655
J 0
(-475 5200);
DISPLAY 0.489362 (-475 5200);
PAINT SKYBLUE (-475 5200);
FORCEPROP 2 LAST $SEC 1
J 0
(-475 5300);
DISPLAY 0.680851 (-475 5300);
PAINT MONO (-475 5300);
DISPLAY INVISIBLE (-475 5300);
FORCEPROP 2 LAST CDS_SEC 1
J 0
(-475 5300);
DISPLAY 1.021277 (-475 5300);
DISPLAY INVISIBLE (-475 5300);
FORCEPROP 1 LASTPIN (-525 5200) $PN 1
J 0
(-515 5180);
DISPLAY 0.489362 (-515 5180);
FORCEPROP 1 LASTPIN (-525 5000) $PN 2
J 0
(-515 4980);
DISPLAY 0.489362 (-515 4980);
FORCEPROP 1 LAST MATERIAL X6S
J 0
(-475 5000);
DISPLAY 0.489362 (-475 5000);
PAINT SKYBLUE (-475 5000);
FORCEPROP 1 LAST TOLERANCE 20%
J 0
(-475 5050);
DISPLAY 0.489362 (-475 5050);
PAINT SKYBLUE (-475 5050);
FORCEPROP 1 LAST VALUE 22UF
J 0
(-475 5150);
DISPLAY 0.489362 (-475 5150);
PAINT SKYBLUE (-475 5150);
FORCEPROP 1 LAST VOLTAGE 4V
J 0
(-475 5100);
DISPLAY 0.489362 (-475 5100);
PAINT SKYBLUE (-475 5100);
FORCEPROP 1 LAST PACK_TYPE C0402
J 0
(-475 4900);
DISPLAY 0.489362 (-475 4900);
PAINT SKYBLUE (-475 4900);
FORCEPROP 2 LAST CDS_LIB pure_quanta
J 0
(-525 5100);
PAINT MONO (-525 5100);
DISPLAY INVISIBLE (-525 5100);
FORCEPROP 1 LAST PATH I172
J 0
(-475 5250);
DISPLAY 0.978723 (-475 5250);
PAINT WHITE (-475 5250);
DISPLAY INVISIBLE (-475 5250);
FORCEPROP 1 LAST PART_NUMBER CH622KMEB02
J 0
(-475 4950);
DISPLAY 0.489362 (-475 4950);
PAINT SKYBLUE (-475 4950);
DISPLAY INVISIBLE (-475 4950);
FORCEADD Q_CAP..1
(-925 5900);
FORCEPROP 1 LAST LOCATION C2649
J 0
(-875 6000);
DISPLAY 0.489362 (-875 6000);
PAINT SKYBLUE (-875 6000);
FORCEPROP 2 LAST $SEC 1
J 0
(-875 6100);
DISPLAY 0.680851 (-875 6100);
PAINT MONO (-875 6100);
DISPLAY INVISIBLE (-875 6100);
FORCEPROP 2 LAST CDS_SEC 1
J 0
(-875 6100);
DISPLAY 1.021277 (-875 6100);
DISPLAY INVISIBLE (-875 6100);
FORCEPROP 1 LASTPIN (-925 6000) $PN 1
J 0
(-915 5980);
DISPLAY 0.489362 (-915 5980);
FORCEPROP 1 LASTPIN (-925 5800) $PN 2
J 0
(-915 5780);
DISPLAY 0.489362 (-915 5780);
FORCEPROP 1 LAST MATERIAL X6S
J 0
(-875 5800);
DISPLAY 0.489362 (-875 5800);
PAINT SKYBLUE (-875 5800);
FORCEPROP 1 LAST TOLERANCE 20%
J 0
(-875 5850);
DISPLAY 0.489362 (-875 5850);
PAINT SKYBLUE (-875 5850);
FORCEPROP 1 LAST VALUE 22UF
J 0
(-875 5950);
DISPLAY 0.489362 (-875 5950);
PAINT SKYBLUE (-875 5950);
FORCEPROP 1 LAST VOLTAGE 4V
J 0
(-875 5900);
DISPLAY 0.489362 (-875 5900);
PAINT SKYBLUE (-875 5900);
FORCEPROP 1 LAST PACK_TYPE C0402
J 0
(-875 5700);
DISPLAY 0.489362 (-875 5700);
PAINT SKYBLUE (-875 5700);
FORCEPROP 2 LAST CDS_LIB pure_quanta
J 0
(-925 5900);
PAINT MONO (-925 5900);
DISPLAY INVISIBLE (-925 5900);
FORCEPROP 1 LAST PATH I173
J 0
(-875 6050);
DISPLAY 0.978723 (-875 6050);
PAINT WHITE (-875 6050);
DISPLAY INVISIBLE (-875 6050);
FORCEPROP 1 LAST PART_NUMBER CH622KMEB02
J 0
(-875 5750);
DISPLAY 0.489362 (-875 5750);
PAINT SKYBLUE (-875 5750);
DISPLAY INVISIBLE (-875 5750);
FORCEADD UNIVERSAL_GND..1
(-525 5525);
FORCEPROP 3 LASTPIN (-525 5575) SIG_NAME GND\g
J 0
(-515 5585);
DISPLAY 0.659574 (-515 5585);
PAINT MONO (-515 5585);
DISPLAY INVISIBLE (-515 5585);
FORCEPROP 2 LAST CDS_LIB pure_quanta_power
J 0
(-525 5525);
PAINT MONO (-525 5525);
DISPLAY INVISIBLE (-525 5525);
FORCEPROP 1 LAST HDL_POWER GND
J 1
(-500 5450);
DISPLAY 0.872340 (-500 5450);
PAINT GREEN (-500 5450);
DISPLAY INVISIBLE (-500 5450);
FORCEPROP 1 LAST PATH I174
J 0
(-450 5525);
DISPLAY 0.872340 (-450 5525);
PAINT AQUA (-450 5525);
DISPLAY INVISIBLE (-450 5525);
FORCEADD Q_CAP..1
(-525 5900);
FORCEPROP 1 LAST LOCATION C2654
J 0
(-475 6000);
DISPLAY 0.489362 (-475 6000);
PAINT SKYBLUE (-475 6000);
FORCEPROP 2 LAST $SEC 1
J 0
(-475 6100);
DISPLAY 0.680851 (-475 6100);
PAINT MONO (-475 6100);
DISPLAY INVISIBLE (-475 6100);
FORCEPROP 2 LAST CDS_SEC 1
J 0
(-475 6100);
DISPLAY 1.021277 (-475 6100);
DISPLAY INVISIBLE (-475 6100);
FORCEPROP 1 LASTPIN (-525 6000) $PN 1
J 0
(-515 5980);
DISPLAY 0.489362 (-515 5980);
FORCEPROP 1 LASTPIN (-525 5800) $PN 2
J 0
(-515 5780);
DISPLAY 0.489362 (-515 5780);
FORCEPROP 1 LAST MATERIAL X6S
J 0
(-475 5800);
DISPLAY 0.489362 (-475 5800);
PAINT SKYBLUE (-475 5800);
FORCEPROP 1 LAST TOLERANCE 20%
J 0
(-475 5850);
DISPLAY 0.489362 (-475 5850);
PAINT SKYBLUE (-475 5850);
FORCEPROP 1 LAST VALUE 22UF
J 0
(-475 5950);
DISPLAY 0.489362 (-475 5950);
PAINT SKYBLUE (-475 5950);
FORCEPROP 1 LAST VOLTAGE 4V
J 0
(-475 5900);
DISPLAY 0.489362 (-475 5900);
PAINT SKYBLUE (-475 5900);
FORCEPROP 1 LAST PACK_TYPE C0402
J 0
(-475 5700);
DISPLAY 0.489362 (-475 5700);
PAINT SKYBLUE (-475 5700);
FORCEPROP 2 LAST CDS_LIB pure_quanta
J 0
(-525 5900);
PAINT MONO (-525 5900);
DISPLAY INVISIBLE (-525 5900);
FORCEPROP 1 LAST PATH I175
J 0
(-475 6050);
DISPLAY 0.978723 (-475 6050);
PAINT WHITE (-475 6050);
DISPLAY INVISIBLE (-475 6050);
FORCEPROP 1 LAST PART_NUMBER CH622KMEB02
J 0
(-475 5750);
DISPLAY 0.489362 (-475 5750);
PAINT SKYBLUE (-475 5750);
DISPLAY INVISIBLE (-475 5750);
FORCEADD Q_CAP..1
(-9100 5150);
FORCEPROP 1 LAST LOCATION C2528
J 0
(-9050 5250);
DISPLAY 0.489362 (-9050 5250);
PAINT SKYBLUE (-9050 5250);
FORCEPROP 2 LAST $SEC 1
J 0
(-9050 5350);
DISPLAY 0.680851 (-9050 5350);
PAINT MONO (-9050 5350);
DISPLAY INVISIBLE (-9050 5350);
FORCEPROP 2 LAST CDS_SEC 1
J 0
(-9050 5350);
DISPLAY 1.021277 (-9050 5350);
DISPLAY INVISIBLE (-9050 5350);
FORCEPROP 1 LASTPIN (-9100 5250) $PN 1
J 0
(-9090 5230);
DISPLAY 0.489362 (-9090 5230);
FORCEPROP 1 LASTPIN (-9100 5050) $PN 2
J 0
(-9090 5030);
DISPLAY 0.489362 (-9090 5030);
FORCEPROP 1 LAST MATERIAL X6S
J 0
(-9050 5050);
DISPLAY 0.489362 (-9050 5050);
PAINT SKYBLUE (-9050 5050);
FORCEPROP 1 LAST TOLERANCE 20%
J 0
(-9050 5100);
DISPLAY 0.489362 (-9050 5100);
PAINT SKYBLUE (-9050 5100);
FORCEPROP 1 LAST VALUE 22UF
J 0
(-9050 5200);
DISPLAY 0.489362 (-9050 5200);
PAINT SKYBLUE (-9050 5200);
FORCEPROP 1 LAST VOLTAGE 4V
J 0
(-9050 5150);
DISPLAY 0.489362 (-9050 5150);
PAINT SKYBLUE (-9050 5150);
FORCEPROP 1 LAST PACK_TYPE C0402
J 0
(-9050 4950);
DISPLAY 0.489362 (-9050 4950);
PAINT SKYBLUE (-9050 4950);
FORCEPROP 2 LAST CDS_LIB pure_quanta
J 0
(-9100 5150);
PAINT MONO (-9100 5150);
DISPLAY INVISIBLE (-9100 5150);
FORCEPROP 1 LAST PATH I18
J 0
(-9050 5300);
DISPLAY 0.978723 (-9050 5300);
PAINT WHITE (-9050 5300);
DISPLAY INVISIBLE (-9050 5300);
FORCEPROP 1 LAST PART_NUMBER CH622KMEB02
J 0
(-9050 5000);
DISPLAY 0.489362 (-9050 5000);
PAINT SKYBLUE (-9050 5000);
DISPLAY INVISIBLE (-9050 5000);
FORCEADD Q_CAP..1
(-8650 4425);
FORCEPROP 1 LAST LOCATION C2536
J 0
(-8600 4525);
DISPLAY 0.489362 (-8600 4525);
PAINT SKYBLUE (-8600 4525);
FORCEPROP 2 LAST $SEC 1
J 0
(-8600 4625);
DISPLAY 0.680851 (-8600 4625);
PAINT MONO (-8600 4625);
DISPLAY INVISIBLE (-8600 4625);
FORCEPROP 2 LAST CDS_SEC 1
J 0
(-8600 4625);
DISPLAY 1.021277 (-8600 4625);
DISPLAY INVISIBLE (-8600 4625);
FORCEPROP 1 LASTPIN (-8650 4525) $PN 1
J 0
(-8640 4505);
DISPLAY 0.489362 (-8640 4505);
FORCEPROP 1 LASTPIN (-8650 4325) $PN 2
J 0
(-8640 4305);
DISPLAY 0.489362 (-8640 4305);
FORCEPROP 1 LAST MATERIAL X6S
J 0
(-8600 4325);
DISPLAY 0.489362 (-8600 4325);
PAINT SKYBLUE (-8600 4325);
FORCEPROP 1 LAST TOLERANCE 20%
J 0
(-8600 4375);
DISPLAY 0.489362 (-8600 4375);
PAINT SKYBLUE (-8600 4375);
FORCEPROP 1 LAST VALUE 22UF
J 0
(-8600 4475);
DISPLAY 0.489362 (-8600 4475);
PAINT SKYBLUE (-8600 4475);
FORCEPROP 1 LAST VOLTAGE 4V
J 0
(-8600 4425);
DISPLAY 0.489362 (-8600 4425);
PAINT SKYBLUE (-8600 4425);
FORCEPROP 1 LAST PACK_TYPE C0402
J 0
(-8600 4225);
DISPLAY 0.489362 (-8600 4225);
PAINT SKYBLUE (-8600 4225);
FORCEPROP 2 LAST CDS_LIB pure_quanta
J 0
(-8650 4425);
PAINT MONO (-8650 4425);
DISPLAY INVISIBLE (-8650 4425);
FORCEPROP 1 LAST PATH I19
J 0
(-8600 4575);
DISPLAY 0.978723 (-8600 4575);
PAINT WHITE (-8600 4575);
DISPLAY INVISIBLE (-8600 4575);
FORCEPROP 1 LAST PART_NUMBER CH622KMEB02
J 0
(-8600 4275);
DISPLAY 0.489362 (-8600 4275);
PAINT SKYBLUE (-8600 4275);
DISPLAY INVISIBLE (-8600 4275);
FORCEADD UNIVERSAL_POWER..1
(-9075 1150);
FORCEPROP 3 LASTPIN (-9075 1100) SIG_NAME PVDDCR_SOC_P0\g
J 0
(-9065 1110);
DISPLAY 0.659574 (-9065 1110);
PAINT MONO (-9065 1110);
DISPLAY INVISIBLE (-9065 1110);
FORCEPROP 1 LAST HDL_POWER PVDDCR_SOC_P0
J 1
(-9075 1200);
DISPLAY 0.489362 (-9075 1200);
PAINT GREEN (-9075 1200);
FORCEPROP 2 LAST CDS_LIB pure_quanta_power
J 0
(-9075 1150);
DISPLAY INVISIBLE (-9075 1150);
FORCEPROP 1 LAST PATH I2
J 0
(-9025 1175);
DISPLAY 0.872340 (-9025 1175);
PAINT AQUA (-9025 1175);
DISPLAY INVISIBLE (-9025 1175);
FORCEADD Q_CAP..1
(-8650 5150);
FORCEPROP 1 LAST LOCATION C2535
J 0
(-8600 5250);
DISPLAY 0.489362 (-8600 5250);
PAINT SKYBLUE (-8600 5250);
FORCEPROP 2 LAST $SEC 1
J 0
(-8600 5350);
DISPLAY 0.680851 (-8600 5350);
PAINT MONO (-8600 5350);
DISPLAY INVISIBLE (-8600 5350);
FORCEPROP 2 LAST CDS_SEC 1
J 0
(-8600 5350);
DISPLAY 1.021277 (-8600 5350);
DISPLAY INVISIBLE (-8600 5350);
FORCEPROP 1 LASTPIN (-8650 5250) $PN 1
J 0
(-8640 5230);
DISPLAY 0.489362 (-8640 5230);
FORCEPROP 1 LASTPIN (-8650 5050) $PN 2
J 0
(-8640 5030);
DISPLAY 0.489362 (-8640 5030);
FORCEPROP 1 LAST MATERIAL X6S
J 0
(-8600 5050);
DISPLAY 0.489362 (-8600 5050);
PAINT SKYBLUE (-8600 5050);
FORCEPROP 1 LAST TOLERANCE 20%
J 0
(-8600 5100);
DISPLAY 0.489362 (-8600 5100);
PAINT SKYBLUE (-8600 5100);
FORCEPROP 1 LAST VALUE 22UF
J 0
(-8600 5200);
DISPLAY 0.489362 (-8600 5200);
PAINT SKYBLUE (-8600 5200);
FORCEPROP 1 LAST VOLTAGE 4V
J 0
(-8600 5150);
DISPLAY 0.489362 (-8600 5150);
PAINT SKYBLUE (-8600 5150);
FORCEPROP 1 LAST PACK_TYPE C0402
J 0
(-8600 4950);
DISPLAY 0.489362 (-8600 4950);
PAINT SKYBLUE (-8600 4950);
FORCEPROP 2 LAST CDS_LIB pure_quanta
J 0
(-8650 5150);
PAINT MONO (-8650 5150);
DISPLAY INVISIBLE (-8650 5150);
FORCEPROP 1 LAST PATH I20
J 0
(-8600 5300);
DISPLAY 0.978723 (-8600 5300);
PAINT WHITE (-8600 5300);
DISPLAY INVISIBLE (-8600 5300);
FORCEPROP 1 LAST PART_NUMBER CH622KMEB02
J 0
(-8600 5000);
DISPLAY 0.489362 (-8600 5000);
PAINT SKYBLUE (-8600 5000);
DISPLAY INVISIBLE (-8600 5000);
FORCEADD UNIVERSAL_POWER..1
(-9100 5425);
FORCEPROP 3 LASTPIN (-9100 5375) SIG_NAME PVDDCR_SOC_P0\g
J 0
(-9090 5385);
DISPLAY 0.659574 (-9090 5385);
PAINT MONO (-9090 5385);
DISPLAY INVISIBLE (-9090 5385);
FORCEPROP 1 LAST HDL_POWER PVDDCR_SOC_P0
J 1
(-9100 5475);
DISPLAY 0.489362 (-9100 5475);
PAINT GREEN (-9100 5475);
FORCEPROP 2 LAST CDS_LIB pure_quanta_power
J 0
(-9100 5425);
DISPLAY INVISIBLE (-9100 5425);
FORCEPROP 1 LAST PATH I21
J 0
(-9050 5450);
DISPLAY 0.872340 (-9050 5450);
PAINT AQUA (-9050 5450);
DISPLAY INVISIBLE (-9050 5450);
FORCEADD Q_CAP..1
(-9100 5900);
FORCEPROP 1 LAST LOCATION C2527
J 0
(-9050 6000);
DISPLAY 0.489362 (-9050 6000);
PAINT SKYBLUE (-9050 6000);
FORCEPROP 2 LAST $SEC 1
J 0
(-9050 6100);
DISPLAY 0.680851 (-9050 6100);
PAINT MONO (-9050 6100);
DISPLAY INVISIBLE (-9050 6100);
FORCEPROP 2 LAST CDS_SEC 1
J 0
(-9050 6100);
DISPLAY 1.021277 (-9050 6100);
DISPLAY INVISIBLE (-9050 6100);
FORCEPROP 1 LASTPIN (-9100 6000) $PN 1
J 0
(-9090 5980);
DISPLAY 0.489362 (-9090 5980);
FORCEPROP 1 LASTPIN (-9100 5800) $PN 2
J 0
(-9090 5780);
DISPLAY 0.489362 (-9090 5780);
FORCEPROP 1 LAST MATERIAL X6S
J 0
(-9050 5800);
DISPLAY 0.489362 (-9050 5800);
PAINT SKYBLUE (-9050 5800);
FORCEPROP 1 LAST TOLERANCE 20%
J 0
(-9050 5850);
DISPLAY 0.489362 (-9050 5850);
PAINT SKYBLUE (-9050 5850);
FORCEPROP 1 LAST VALUE 22UF
J 0
(-9050 5950);
DISPLAY 0.489362 (-9050 5950);
PAINT SKYBLUE (-9050 5950);
FORCEPROP 1 LAST VOLTAGE 4V
J 0
(-9050 5900);
DISPLAY 0.489362 (-9050 5900);
PAINT SKYBLUE (-9050 5900);
FORCEPROP 1 LAST PACK_TYPE C0402
J 0
(-9050 5700);
DISPLAY 0.489362 (-9050 5700);
PAINT SKYBLUE (-9050 5700);
FORCEPROP 2 LAST CDS_LIB pure_quanta
J 0
(-9100 5900);
PAINT MONO (-9100 5900);
DISPLAY INVISIBLE (-9100 5900);
FORCEPROP 1 LAST PATH I22
J 0
(-9050 6050);
DISPLAY 0.978723 (-9050 6050);
PAINT WHITE (-9050 6050);
DISPLAY INVISIBLE (-9050 6050);
FORCEPROP 1 LAST PART_NUMBER CH622KMEB02
J 0
(-9050 5750);
DISPLAY 0.489362 (-9050 5750);
PAINT SKYBLUE (-9050 5750);
DISPLAY INVISIBLE (-9050 5750);
FORCEADD UNIVERSAL_POWER..1
(-9100 6175);
FORCEPROP 3 LASTPIN (-9100 6125) SIG_NAME PVDDCR_SOC_P0\g
J 0
(-9090 6135);
DISPLAY 0.659574 (-9090 6135);
PAINT MONO (-9090 6135);
DISPLAY INVISIBLE (-9090 6135);
FORCEPROP 1 LAST HDL_POWER PVDDCR_SOC_P0
J 1
(-9100 6225);
DISPLAY 0.489362 (-9100 6225);
PAINT GREEN (-9100 6225);
FORCEPROP 2 LAST CDS_LIB pure_quanta_power
J 0
(-9100 6175);
DISPLAY INVISIBLE (-9100 6175);
FORCEPROP 1 LAST PATH I23
J 0
(-9050 6200);
DISPLAY 0.872340 (-9050 6200);
PAINT AQUA (-9050 6200);
DISPLAY INVISIBLE (-9050 6200);
FORCEADD Q_CAP..1
(-8650 5900);
FORCEPROP 1 LAST LOCATION C2534
J 0
(-8600 6000);
DISPLAY 0.489362 (-8600 6000);
PAINT SKYBLUE (-8600 6000);
FORCEPROP 2 LAST $SEC 1
J 0
(-8600 6100);
DISPLAY 0.680851 (-8600 6100);
PAINT MONO (-8600 6100);
DISPLAY INVISIBLE (-8600 6100);
FORCEPROP 2 LAST CDS_SEC 1
J 0
(-8600 6100);
DISPLAY 1.021277 (-8600 6100);
DISPLAY INVISIBLE (-8600 6100);
FORCEPROP 1 LASTPIN (-8650 6000) $PN 1
J 0
(-8640 5980);
DISPLAY 0.489362 (-8640 5980);
FORCEPROP 1 LASTPIN (-8650 5800) $PN 2
J 0
(-8640 5780);
DISPLAY 0.489362 (-8640 5780);
FORCEPROP 1 LAST MATERIAL X6S
J 0
(-8600 5800);
DISPLAY 0.489362 (-8600 5800);
PAINT SKYBLUE (-8600 5800);
FORCEPROP 1 LAST TOLERANCE 20%
J 0
(-8600 5850);
DISPLAY 0.489362 (-8600 5850);
PAINT SKYBLUE (-8600 5850);
FORCEPROP 1 LAST VALUE 22UF
J 0
(-8600 5950);
DISPLAY 0.489362 (-8600 5950);
PAINT SKYBLUE (-8600 5950);
FORCEPROP 1 LAST VOLTAGE 4V
J 0
(-8600 5900);
DISPLAY 0.489362 (-8600 5900);
PAINT SKYBLUE (-8600 5900);
FORCEPROP 1 LAST PACK_TYPE C0402
J 0
(-8600 5700);
DISPLAY 0.489362 (-8600 5700);
PAINT SKYBLUE (-8600 5700);
FORCEPROP 2 LAST CDS_LIB pure_quanta
J 0
(-8650 5900);
PAINT MONO (-8650 5900);
DISPLAY INVISIBLE (-8650 5900);
FORCEPROP 1 LAST PATH I24
J 0
(-8600 6050);
DISPLAY 0.978723 (-8600 6050);
PAINT WHITE (-8600 6050);
DISPLAY INVISIBLE (-8600 6050);
FORCEPROP 1 LAST PART_NUMBER CH622KMEB02
J 0
(-8600 5750);
DISPLAY 0.489362 (-8600 5750);
PAINT SKYBLUE (-8600 5750);
DISPLAY INVISIBLE (-8600 5750);
FORCEADD Q_CAP..1
(-8175 875);
FORCEPROP 1 LAST LOCATION C3927
J 0
(-8125 975);
DISPLAY 0.489362 (-8125 975);
PAINT SKYBLUE (-8125 975);
FORCEPROP 2 LAST $SEC 1
J 0
(-8125 1075);
DISPLAY 0.680851 (-8125 1075);
PAINT MONO (-8125 1075);
DISPLAY INVISIBLE (-8125 1075);
FORCEPROP 2 LAST CDS_SEC 1
J 0
(-8125 1075);
DISPLAY 1.021277 (-8125 1075);
DISPLAY INVISIBLE (-8125 1075);
FORCEPROP 1 LASTPIN (-8175 975) $PN 1
J 0
(-8165 955);
DISPLAY 0.489362 (-8165 955);
FORCEPROP 1 LASTPIN (-8175 775) $PN 2
J 0
(-8165 755);
DISPLAY 0.489362 (-8165 755);
FORCEPROP 1 LAST MATERIAL X6S
J 0
(-8125 775);
DISPLAY 0.489362 (-8125 775);
PAINT SKYBLUE (-8125 775);
FORCEPROP 1 LAST TOLERANCE 20%
J 0
(-8125 825);
DISPLAY 0.489362 (-8125 825);
PAINT SKYBLUE (-8125 825);
FORCEPROP 1 LAST VALUE 22UF
J 0
(-8125 925);
DISPLAY 0.489362 (-8125 925);
PAINT SKYBLUE (-8125 925);
FORCEPROP 1 LAST VOLTAGE 4V
J 0
(-8125 875);
DISPLAY 0.489362 (-8125 875);
PAINT SKYBLUE (-8125 875);
FORCEPROP 1 LAST PACK_TYPE C0402
J 0
(-8125 675);
DISPLAY 0.489362 (-8125 675);
PAINT SKYBLUE (-8125 675);
FORCEPROP 2 LAST CDS_LIB pure_quanta
J 0
(-8175 875);
PAINT MONO (-8175 875);
DISPLAY INVISIBLE (-8175 875);
FORCEPROP 1 LAST PATH I25
J 0
(-8125 1025);
DISPLAY 0.978723 (-8125 1025);
PAINT WHITE (-8125 1025);
DISPLAY INVISIBLE (-8125 1025);
FORCEPROP 1 LAST PART_NUMBER CH622KMEB02
J 0
(-8125 725);
DISPLAY 0.489362 (-8125 725);
PAINT SKYBLUE (-8125 725);
DISPLAY INVISIBLE (-8125 725);
FORCEADD Q_CAP..1
(-7725 875);
FORCEPROP 1 LAST LOCATION C3928
J 0
(-7675 975);
DISPLAY 0.489362 (-7675 975);
PAINT SKYBLUE (-7675 975);
FORCEPROP 2 LAST $SEC 1
J 0
(-7675 1075);
DISPLAY 0.680851 (-7675 1075);
PAINT MONO (-7675 1075);
DISPLAY INVISIBLE (-7675 1075);
FORCEPROP 2 LAST CDS_SEC 1
J 0
(-7675 1075);
DISPLAY 1.021277 (-7675 1075);
DISPLAY INVISIBLE (-7675 1075);
FORCEPROP 1 LASTPIN (-7725 975) $PN 1
J 0
(-7715 955);
DISPLAY 0.489362 (-7715 955);
FORCEPROP 1 LASTPIN (-7725 775) $PN 2
J 0
(-7715 755);
DISPLAY 0.489362 (-7715 755);
FORCEPROP 1 LAST MATERIAL X6S
J 0
(-7675 775);
DISPLAY 0.489362 (-7675 775);
PAINT SKYBLUE (-7675 775);
FORCEPROP 1 LAST TOLERANCE 20%
J 0
(-7675 825);
DISPLAY 0.489362 (-7675 825);
PAINT SKYBLUE (-7675 825);
FORCEPROP 1 LAST VALUE 22UF
J 0
(-7675 925);
DISPLAY 0.489362 (-7675 925);
PAINT SKYBLUE (-7675 925);
FORCEPROP 1 LAST VOLTAGE 4V
J 0
(-7675 875);
DISPLAY 0.489362 (-7675 875);
PAINT SKYBLUE (-7675 875);
FORCEPROP 1 LAST PACK_TYPE C0402
J 0
(-7675 675);
DISPLAY 0.489362 (-7675 675);
PAINT SKYBLUE (-7675 675);
FORCEPROP 2 LAST CDS_LIB pure_quanta
J 0
(-7725 875);
PAINT MONO (-7725 875);
DISPLAY INVISIBLE (-7725 875);
FORCEPROP 1 LAST PATH I26
J 0
(-7675 1025);
DISPLAY 0.978723 (-7675 1025);
PAINT WHITE (-7675 1025);
DISPLAY INVISIBLE (-7675 1025);
FORCEPROP 1 LAST PART_NUMBER CH622KMEB02
J 0
(-7675 725);
DISPLAY 0.489362 (-7675 725);
PAINT SKYBLUE (-7675 725);
DISPLAY INVISIBLE (-7675 725);
FORCEADD Q_CAP..1
(-7275 875);
FORCEPROP 1 LAST LOCATION C3929
J 0
(-7225 975);
DISPLAY 0.489362 (-7225 975);
PAINT SKYBLUE (-7225 975);
FORCEPROP 2 LAST $SEC 1
J 0
(-7225 1075);
DISPLAY 0.680851 (-7225 1075);
PAINT MONO (-7225 1075);
DISPLAY INVISIBLE (-7225 1075);
FORCEPROP 2 LAST CDS_SEC 1
J 0
(-7225 1075);
DISPLAY 1.021277 (-7225 1075);
DISPLAY INVISIBLE (-7225 1075);
FORCEPROP 1 LASTPIN (-7275 975) $PN 1
J 0
(-7265 955);
DISPLAY 0.489362 (-7265 955);
FORCEPROP 1 LASTPIN (-7275 775) $PN 2
J 0
(-7265 755);
DISPLAY 0.489362 (-7265 755);
FORCEPROP 1 LAST MATERIAL X6S
J 0
(-7225 775);
DISPLAY 0.489362 (-7225 775);
PAINT SKYBLUE (-7225 775);
FORCEPROP 1 LAST TOLERANCE 20%
J 0
(-7225 825);
DISPLAY 0.489362 (-7225 825);
PAINT SKYBLUE (-7225 825);
FORCEPROP 1 LAST VALUE 22UF
J 0
(-7225 925);
DISPLAY 0.489362 (-7225 925);
PAINT SKYBLUE (-7225 925);
FORCEPROP 1 LAST VOLTAGE 4V
J 0
(-7225 875);
DISPLAY 0.489362 (-7225 875);
PAINT SKYBLUE (-7225 875);
FORCEPROP 1 LAST PACK_TYPE C0402
J 0
(-7225 675);
DISPLAY 0.489362 (-7225 675);
PAINT SKYBLUE (-7225 675);
FORCEPROP 2 LAST CDS_LIB pure_quanta
J 0
(-7275 875);
PAINT MONO (-7275 875);
DISPLAY INVISIBLE (-7275 875);
FORCEPROP 1 LAST PATH I27
J 0
(-7225 1025);
DISPLAY 0.978723 (-7225 1025);
PAINT WHITE (-7225 1025);
DISPLAY INVISIBLE (-7225 1025);
FORCEPROP 1 LAST PART_NUMBER CH622KMEB02
J 0
(-7225 725);
DISPLAY 0.489362 (-7225 725);
PAINT SKYBLUE (-7225 725);
DISPLAY INVISIBLE (-7225 725);
FORCEADD Q_CAP..1
(-8175 1575);
FORCEPROP 1 LAST LOCATION C2547
J 0
(-8125 1675);
DISPLAY 0.489362 (-8125 1675);
PAINT SKYBLUE (-8125 1675);
FORCEPROP 2 LAST $SEC 1
J 0
(-8125 1775);
DISPLAY 0.680851 (-8125 1775);
PAINT MONO (-8125 1775);
DISPLAY INVISIBLE (-8125 1775);
FORCEPROP 2 LAST CDS_SEC 1
J 0
(-8125 1775);
DISPLAY 1.021277 (-8125 1775);
DISPLAY INVISIBLE (-8125 1775);
FORCEPROP 1 LASTPIN (-8175 1675) $PN 1
J 0
(-8165 1655);
DISPLAY 0.489362 (-8165 1655);
FORCEPROP 1 LASTPIN (-8175 1475) $PN 2
J 0
(-8165 1455);
DISPLAY 0.489362 (-8165 1455);
FORCEPROP 1 LAST MATERIAL X6S
J 0
(-8125 1475);
DISPLAY 0.489362 (-8125 1475);
PAINT SKYBLUE (-8125 1475);
FORCEPROP 1 LAST TOLERANCE 20%
J 0
(-8125 1525);
DISPLAY 0.489362 (-8125 1525);
PAINT SKYBLUE (-8125 1525);
FORCEPROP 1 LAST VALUE 22UF
J 0
(-8125 1625);
DISPLAY 0.489362 (-8125 1625);
PAINT SKYBLUE (-8125 1625);
FORCEPROP 1 LAST VOLTAGE 4V
J 0
(-8125 1575);
DISPLAY 0.489362 (-8125 1575);
PAINT SKYBLUE (-8125 1575);
FORCEPROP 1 LAST PACK_TYPE C0402
J 0
(-8125 1375);
DISPLAY 0.489362 (-8125 1375);
PAINT SKYBLUE (-8125 1375);
FORCEPROP 2 LAST CDS_LIB pure_quanta
J 0
(-8175 1575);
PAINT MONO (-8175 1575);
DISPLAY INVISIBLE (-8175 1575);
FORCEPROP 1 LAST PATH I28
J 0
(-8125 1725);
DISPLAY 0.978723 (-8125 1725);
PAINT WHITE (-8125 1725);
DISPLAY INVISIBLE (-8125 1725);
FORCEPROP 1 LAST PART_NUMBER CH622KMEB02
J 0
(-8125 1425);
DISPLAY 0.489362 (-8125 1425);
PAINT SKYBLUE (-8125 1425);
DISPLAY INVISIBLE (-8125 1425);
FORCEADD Q_CAP..1
(-7725 1575);
FORCEPROP 1 LAST LOCATION C2554
J 0
(-7675 1675);
DISPLAY 0.489362 (-7675 1675);
PAINT SKYBLUE (-7675 1675);
FORCEPROP 2 LAST $SEC 1
J 0
(-7675 1775);
DISPLAY 0.680851 (-7675 1775);
PAINT MONO (-7675 1775);
DISPLAY INVISIBLE (-7675 1775);
FORCEPROP 2 LAST CDS_SEC 1
J 0
(-7675 1775);
DISPLAY 1.021277 (-7675 1775);
DISPLAY INVISIBLE (-7675 1775);
FORCEPROP 1 LASTPIN (-7725 1675) $PN 1
J 0
(-7715 1655);
DISPLAY 0.489362 (-7715 1655);
FORCEPROP 1 LASTPIN (-7725 1475) $PN 2
J 0
(-7715 1455);
DISPLAY 0.489362 (-7715 1455);
FORCEPROP 1 LAST MATERIAL X6S
J 0
(-7675 1475);
DISPLAY 0.489362 (-7675 1475);
PAINT SKYBLUE (-7675 1475);
FORCEPROP 1 LAST TOLERANCE 20%
J 0
(-7675 1525);
DISPLAY 0.489362 (-7675 1525);
PAINT SKYBLUE (-7675 1525);
FORCEPROP 1 LAST VALUE 22UF
J 0
(-7675 1625);
DISPLAY 0.489362 (-7675 1625);
PAINT SKYBLUE (-7675 1625);
FORCEPROP 1 LAST VOLTAGE 4V
J 0
(-7675 1575);
DISPLAY 0.489362 (-7675 1575);
PAINT SKYBLUE (-7675 1575);
FORCEPROP 1 LAST PACK_TYPE C0402
J 0
(-7675 1375);
DISPLAY 0.489362 (-7675 1375);
PAINT SKYBLUE (-7675 1375);
FORCEPROP 2 LAST CDS_LIB pure_quanta
J 0
(-7725 1575);
PAINT MONO (-7725 1575);
DISPLAY INVISIBLE (-7725 1575);
FORCEPROP 1 LAST PATH I29
J 0
(-7675 1725);
DISPLAY 0.978723 (-7675 1725);
PAINT WHITE (-7675 1725);
DISPLAY INVISIBLE (-7675 1725);
FORCEPROP 1 LAST PART_NUMBER CH622KMEB02
J 0
(-7675 1425);
DISPLAY 0.489362 (-7675 1425);
PAINT SKYBLUE (-7675 1425);
DISPLAY INVISIBLE (-7675 1425);
FORCEADD Q_CAP..1
(-8625 875);
FORCEPROP 1 LAST LOCATION C3926
J 0
(-8575 975);
DISPLAY 0.489362 (-8575 975);
PAINT SKYBLUE (-8575 975);
FORCEPROP 2 LAST $SEC 1
J 0
(-8575 1075);
DISPLAY 0.680851 (-8575 1075);
PAINT MONO (-8575 1075);
DISPLAY INVISIBLE (-8575 1075);
FORCEPROP 2 LAST CDS_SEC 1
J 0
(-8575 1075);
DISPLAY 1.021277 (-8575 1075);
DISPLAY INVISIBLE (-8575 1075);
FORCEPROP 1 LASTPIN (-8625 975) $PN 1
J 0
(-8615 955);
DISPLAY 0.489362 (-8615 955);
FORCEPROP 1 LASTPIN (-8625 775) $PN 2
J 0
(-8615 755);
DISPLAY 0.489362 (-8615 755);
FORCEPROP 1 LAST MATERIAL X6S
J 0
(-8575 775);
DISPLAY 0.489362 (-8575 775);
PAINT SKYBLUE (-8575 775);
FORCEPROP 1 LAST TOLERANCE 20%
J 0
(-8575 825);
DISPLAY 0.489362 (-8575 825);
PAINT SKYBLUE (-8575 825);
FORCEPROP 1 LAST VALUE 22UF
J 0
(-8575 925);
DISPLAY 0.489362 (-8575 925);
PAINT SKYBLUE (-8575 925);
FORCEPROP 1 LAST VOLTAGE 4V
J 0
(-8575 875);
DISPLAY 0.489362 (-8575 875);
PAINT SKYBLUE (-8575 875);
FORCEPROP 1 LAST PACK_TYPE C0402
J 0
(-8575 675);
DISPLAY 0.489362 (-8575 675);
PAINT SKYBLUE (-8575 675);
FORCEPROP 2 LAST CDS_LIB pure_quanta
J 0
(-8625 875);
PAINT MONO (-8625 875);
DISPLAY INVISIBLE (-8625 875);
FORCEPROP 1 LAST PATH I3
J 0
(-8575 1025);
DISPLAY 0.978723 (-8575 1025);
PAINT WHITE (-8575 1025);
DISPLAY INVISIBLE (-8575 1025);
FORCEPROP 1 LAST PART_NUMBER CH622KMEB02
J 0
(-8575 725);
DISPLAY 0.489362 (-8575 725);
PAINT SKYBLUE (-8575 725);
DISPLAY INVISIBLE (-8575 725);
FORCEADD Q_CAP..1
(-7275 1575);
FORCEPROP 1 LAST LOCATION C2561
J 0
(-7225 1675);
DISPLAY 0.489362 (-7225 1675);
PAINT SKYBLUE (-7225 1675);
FORCEPROP 2 LAST $SEC 1
J 0
(-7225 1775);
DISPLAY 0.680851 (-7225 1775);
PAINT MONO (-7225 1775);
DISPLAY INVISIBLE (-7225 1775);
FORCEPROP 2 LAST CDS_SEC 1
J 0
(-7225 1775);
DISPLAY 1.021277 (-7225 1775);
DISPLAY INVISIBLE (-7225 1775);
FORCEPROP 1 LASTPIN (-7275 1675) $PN 1
J 0
(-7265 1655);
DISPLAY 0.489362 (-7265 1655);
FORCEPROP 1 LASTPIN (-7275 1475) $PN 2
J 0
(-7265 1455);
DISPLAY 0.489362 (-7265 1455);
FORCEPROP 1 LAST MATERIAL X6S
J 0
(-7225 1475);
DISPLAY 0.489362 (-7225 1475);
PAINT SKYBLUE (-7225 1475);
FORCEPROP 1 LAST TOLERANCE 20%
J 0
(-7225 1525);
DISPLAY 0.489362 (-7225 1525);
PAINT SKYBLUE (-7225 1525);
FORCEPROP 1 LAST VALUE 22UF
J 0
(-7225 1625);
DISPLAY 0.489362 (-7225 1625);
PAINT SKYBLUE (-7225 1625);
FORCEPROP 1 LAST VOLTAGE 4V
J 0
(-7225 1575);
DISPLAY 0.489362 (-7225 1575);
PAINT SKYBLUE (-7225 1575);
FORCEPROP 1 LAST PACK_TYPE C0402
J 0
(-7225 1375);
DISPLAY 0.489362 (-7225 1375);
PAINT SKYBLUE (-7225 1375);
FORCEPROP 2 LAST CDS_LIB pure_quanta
J 0
(-7275 1575);
PAINT MONO (-7275 1575);
DISPLAY INVISIBLE (-7275 1575);
FORCEPROP 1 LAST PATH I30
J 0
(-7225 1725);
DISPLAY 0.978723 (-7225 1725);
PAINT WHITE (-7225 1725);
DISPLAY INVISIBLE (-7225 1725);
FORCEPROP 1 LAST PART_NUMBER CH622KMEB02
J 0
(-7225 1425);
DISPLAY 0.489362 (-7225 1425);
PAINT SKYBLUE (-7225 1425);
DISPLAY INVISIBLE (-7225 1425);
FORCEADD Q_CAP..1
(-6825 875);
FORCEPROP 1 LAST LOCATION C3930
J 0
(-6775 975);
DISPLAY 0.489362 (-6775 975);
PAINT SKYBLUE (-6775 975);
FORCEPROP 2 LAST $SEC 1
J 0
(-6775 1075);
DISPLAY 0.680851 (-6775 1075);
PAINT MONO (-6775 1075);
DISPLAY INVISIBLE (-6775 1075);
FORCEPROP 2 LAST CDS_SEC 1
J 0
(-6775 1075);
DISPLAY 1.021277 (-6775 1075);
DISPLAY INVISIBLE (-6775 1075);
FORCEPROP 1 LASTPIN (-6825 975) $PN 1
J 0
(-6815 955);
DISPLAY 0.489362 (-6815 955);
FORCEPROP 1 LASTPIN (-6825 775) $PN 2
J 0
(-6815 755);
DISPLAY 0.489362 (-6815 755);
FORCEPROP 1 LAST MATERIAL X6S
J 0
(-6775 775);
DISPLAY 0.489362 (-6775 775);
PAINT SKYBLUE (-6775 775);
FORCEPROP 1 LAST TOLERANCE 20%
J 0
(-6775 825);
DISPLAY 0.489362 (-6775 825);
PAINT SKYBLUE (-6775 825);
FORCEPROP 1 LAST VALUE 22UF
J 0
(-6775 925);
DISPLAY 0.489362 (-6775 925);
PAINT SKYBLUE (-6775 925);
FORCEPROP 1 LAST VOLTAGE 4V
J 0
(-6775 875);
DISPLAY 0.489362 (-6775 875);
PAINT SKYBLUE (-6775 875);
FORCEPROP 1 LAST PACK_TYPE C0402
J 0
(-6775 675);
DISPLAY 0.489362 (-6775 675);
PAINT SKYBLUE (-6775 675);
FORCEPROP 2 LAST CDS_LIB pure_quanta
J 0
(-6825 875);
PAINT MONO (-6825 875);
DISPLAY INVISIBLE (-6825 875);
FORCEPROP 1 LAST PATH I31
J 0
(-6775 1025);
DISPLAY 0.978723 (-6775 1025);
PAINT WHITE (-6775 1025);
DISPLAY INVISIBLE (-6775 1025);
FORCEPROP 1 LAST PART_NUMBER CH622KMEB02
J 0
(-6775 725);
DISPLAY 0.489362 (-6775 725);
PAINT SKYBLUE (-6775 725);
DISPLAY INVISIBLE (-6775 725);
FORCEADD UNIVERSAL_GND..1
(-6375 500);
FORCEPROP 3 LASTPIN (-6375 550) SIG_NAME GND\g
J 0
(-6365 560);
DISPLAY 0.659574 (-6365 560);
PAINT MONO (-6365 560);
DISPLAY INVISIBLE (-6365 560);
FORCEPROP 2 LAST CDS_LIB pure_quanta_power
J 0
(-6375 500);
PAINT MONO (-6375 500);
DISPLAY INVISIBLE (-6375 500);
FORCEPROP 1 LAST HDL_POWER GND
J 1
(-6350 425);
DISPLAY 0.872340 (-6350 425);
PAINT GREEN (-6350 425);
DISPLAY INVISIBLE (-6350 425);
FORCEPROP 1 LAST PATH I32
J 0
(-6300 500);
DISPLAY 0.872340 (-6300 500);
PAINT AQUA (-6300 500);
DISPLAY INVISIBLE (-6300 500);
FORCEADD Q_CAP..1
(-6375 875);
FORCEPROP 1 LAST LOCATION C3931
J 0
(-6325 975);
DISPLAY 0.489362 (-6325 975);
PAINT SKYBLUE (-6325 975);
FORCEPROP 2 LAST $SEC 1
J 0
(-6325 1075);
DISPLAY 0.680851 (-6325 1075);
PAINT MONO (-6325 1075);
DISPLAY INVISIBLE (-6325 1075);
FORCEPROP 2 LAST CDS_SEC 1
J 0
(-6325 1075);
DISPLAY 1.021277 (-6325 1075);
DISPLAY INVISIBLE (-6325 1075);
FORCEPROP 1 LASTPIN (-6375 975) $PN 1
J 0
(-6365 955);
DISPLAY 0.489362 (-6365 955);
FORCEPROP 1 LASTPIN (-6375 775) $PN 2
J 0
(-6365 755);
DISPLAY 0.489362 (-6365 755);
FORCEPROP 1 LAST MATERIAL X6S
J 0
(-6325 775);
DISPLAY 0.489362 (-6325 775);
PAINT SKYBLUE (-6325 775);
FORCEPROP 1 LAST TOLERANCE 20%
J 0
(-6325 825);
DISPLAY 0.489362 (-6325 825);
PAINT SKYBLUE (-6325 825);
FORCEPROP 1 LAST VALUE 22UF
J 0
(-6325 925);
DISPLAY 0.489362 (-6325 925);
PAINT SKYBLUE (-6325 925);
FORCEPROP 1 LAST VOLTAGE 4V
J 0
(-6325 875);
DISPLAY 0.489362 (-6325 875);
PAINT SKYBLUE (-6325 875);
FORCEPROP 1 LAST PACK_TYPE C0402
J 0
(-6325 675);
DISPLAY 0.489362 (-6325 675);
PAINT SKYBLUE (-6325 675);
FORCEPROP 2 LAST CDS_LIB pure_quanta
J 0
(-6375 875);
PAINT MONO (-6375 875);
DISPLAY INVISIBLE (-6375 875);
FORCEPROP 1 LAST PATH I33
J 0
(-6325 1025);
DISPLAY 0.978723 (-6325 1025);
PAINT WHITE (-6325 1025);
DISPLAY INVISIBLE (-6325 1025);
FORCEPROP 1 LAST PART_NUMBER CH622KMEB02
J 0
(-6325 725);
DISPLAY 0.489362 (-6325 725);
PAINT SKYBLUE (-6325 725);
DISPLAY INVISIBLE (-6325 725);
FORCEADD Q_CAP..1
(-6825 1575);
FORCEPROP 1 LAST LOCATION C2568
J 0
(-6775 1675);
DISPLAY 0.489362 (-6775 1675);
PAINT SKYBLUE (-6775 1675);
FORCEPROP 2 LAST $SEC 1
J 0
(-6775 1775);
DISPLAY 0.680851 (-6775 1775);
PAINT MONO (-6775 1775);
DISPLAY INVISIBLE (-6775 1775);
FORCEPROP 2 LAST CDS_SEC 1
J 0
(-6775 1775);
DISPLAY 1.021277 (-6775 1775);
DISPLAY INVISIBLE (-6775 1775);
FORCEPROP 1 LASTPIN (-6825 1675) $PN 1
J 0
(-6815 1655);
DISPLAY 0.489362 (-6815 1655);
FORCEPROP 1 LASTPIN (-6825 1475) $PN 2
J 0
(-6815 1455);
DISPLAY 0.489362 (-6815 1455);
FORCEPROP 1 LAST MATERIAL X6S
J 0
(-6775 1475);
DISPLAY 0.489362 (-6775 1475);
PAINT SKYBLUE (-6775 1475);
FORCEPROP 1 LAST TOLERANCE 20%
J 0
(-6775 1525);
DISPLAY 0.489362 (-6775 1525);
PAINT SKYBLUE (-6775 1525);
FORCEPROP 1 LAST VALUE 22UF
J 0
(-6775 1625);
DISPLAY 0.489362 (-6775 1625);
PAINT SKYBLUE (-6775 1625);
FORCEPROP 1 LAST VOLTAGE 4V
J 0
(-6775 1575);
DISPLAY 0.489362 (-6775 1575);
PAINT SKYBLUE (-6775 1575);
FORCEPROP 1 LAST PACK_TYPE C0402
J 0
(-6775 1375);
DISPLAY 0.489362 (-6775 1375);
PAINT SKYBLUE (-6775 1375);
FORCEPROP 2 LAST CDS_LIB pure_quanta
J 0
(-6825 1575);
PAINT MONO (-6825 1575);
DISPLAY INVISIBLE (-6825 1575);
FORCEPROP 1 LAST PATH I34
J 0
(-6775 1725);
DISPLAY 0.978723 (-6775 1725);
PAINT WHITE (-6775 1725);
DISPLAY INVISIBLE (-6775 1725);
FORCEPROP 1 LAST PART_NUMBER CH622KMEB02
J 0
(-6775 1425);
DISPLAY 0.489362 (-6775 1425);
PAINT SKYBLUE (-6775 1425);
DISPLAY INVISIBLE (-6775 1425);
FORCEADD Q_CAP..1
(-6375 1575);
FORCEPROP 1 LAST LOCATION C2575
J 0
(-6325 1675);
DISPLAY 0.489362 (-6325 1675);
PAINT SKYBLUE (-6325 1675);
FORCEPROP 2 LAST $SEC 1
J 0
(-6325 1775);
DISPLAY 0.680851 (-6325 1775);
PAINT MONO (-6325 1775);
DISPLAY INVISIBLE (-6325 1775);
FORCEPROP 2 LAST CDS_SEC 1
J 0
(-6325 1775);
DISPLAY 1.021277 (-6325 1775);
DISPLAY INVISIBLE (-6325 1775);
FORCEPROP 1 LASTPIN (-6375 1675) $PN 1
J 0
(-6365 1655);
DISPLAY 0.489362 (-6365 1655);
FORCEPROP 1 LASTPIN (-6375 1475) $PN 2
J 0
(-6365 1455);
DISPLAY 0.489362 (-6365 1455);
FORCEPROP 1 LAST MATERIAL X6S
J 0
(-6325 1475);
DISPLAY 0.489362 (-6325 1475);
PAINT SKYBLUE (-6325 1475);
FORCEPROP 1 LAST TOLERANCE 20%
J 0
(-6325 1525);
DISPLAY 0.489362 (-6325 1525);
PAINT SKYBLUE (-6325 1525);
FORCEPROP 1 LAST VALUE 22UF
J 0
(-6325 1625);
DISPLAY 0.489362 (-6325 1625);
PAINT SKYBLUE (-6325 1625);
FORCEPROP 1 LAST VOLTAGE 4V
J 0
(-6325 1575);
DISPLAY 0.489362 (-6325 1575);
PAINT SKYBLUE (-6325 1575);
FORCEPROP 1 LAST PACK_TYPE C0402
J 0
(-6325 1375);
DISPLAY 0.489362 (-6325 1375);
PAINT SKYBLUE (-6325 1375);
FORCEPROP 2 LAST CDS_LIB pure_quanta
J 0
(-6375 1575);
PAINT MONO (-6375 1575);
DISPLAY INVISIBLE (-6375 1575);
FORCEPROP 1 LAST PATH I35
J 0
(-6325 1725);
DISPLAY 0.978723 (-6325 1725);
PAINT WHITE (-6325 1725);
DISPLAY INVISIBLE (-6325 1725);
FORCEPROP 1 LAST PART_NUMBER CH622KMEB02
J 0
(-6325 1425);
DISPLAY 0.489362 (-6325 1425);
PAINT SKYBLUE (-6325 1425);
DISPLAY INVISIBLE (-6325 1425);
FORCEADD Q_CAP..1
(-8175 2300);
FORCEPROP 1 LAST LOCATION C2546
J 0
(-8125 2400);
DISPLAY 0.489362 (-8125 2400);
PAINT SKYBLUE (-8125 2400);
FORCEPROP 2 LAST $SEC 1
J 0
(-8125 2500);
DISPLAY 0.680851 (-8125 2500);
PAINT MONO (-8125 2500);
DISPLAY INVISIBLE (-8125 2500);
FORCEPROP 2 LAST CDS_SEC 1
J 0
(-8125 2500);
DISPLAY 1.021277 (-8125 2500);
DISPLAY INVISIBLE (-8125 2500);
FORCEPROP 1 LASTPIN (-8175 2400) $PN 1
J 0
(-8165 2380);
DISPLAY 0.489362 (-8165 2380);
FORCEPROP 1 LASTPIN (-8175 2200) $PN 2
J 0
(-8165 2180);
DISPLAY 0.489362 (-8165 2180);
FORCEPROP 1 LAST MATERIAL X6S
J 0
(-8125 2200);
DISPLAY 0.489362 (-8125 2200);
PAINT SKYBLUE (-8125 2200);
FORCEPROP 1 LAST TOLERANCE 20%
J 0
(-8125 2250);
DISPLAY 0.489362 (-8125 2250);
PAINT SKYBLUE (-8125 2250);
FORCEPROP 1 LAST VALUE 22UF
J 0
(-8125 2350);
DISPLAY 0.489362 (-8125 2350);
PAINT SKYBLUE (-8125 2350);
FORCEPROP 1 LAST VOLTAGE 4V
J 0
(-8125 2300);
DISPLAY 0.489362 (-8125 2300);
PAINT SKYBLUE (-8125 2300);
FORCEPROP 1 LAST PACK_TYPE C0402
J 0
(-8125 2100);
DISPLAY 0.489362 (-8125 2100);
PAINT SKYBLUE (-8125 2100);
FORCEPROP 2 LAST CDS_LIB pure_quanta
J 0
(-8175 2300);
PAINT MONO (-8175 2300);
DISPLAY INVISIBLE (-8175 2300);
FORCEPROP 1 LAST PATH I36
J 0
(-8125 2450);
DISPLAY 0.978723 (-8125 2450);
PAINT WHITE (-8125 2450);
DISPLAY INVISIBLE (-8125 2450);
FORCEPROP 1 LAST PART_NUMBER CH622KMEB02
J 0
(-8125 2150);
DISPLAY 0.489362 (-8125 2150);
PAINT SKYBLUE (-8125 2150);
DISPLAY INVISIBLE (-8125 2150);
FORCEADD Q_CAP..1
(-8175 3000);
FORCEPROP 1 LAST LOCATION C2545
J 0
(-8125 3100);
DISPLAY 0.489362 (-8125 3100);
PAINT SKYBLUE (-8125 3100);
FORCEPROP 2 LAST $SEC 1
J 0
(-8125 3200);
DISPLAY 0.680851 (-8125 3200);
PAINT MONO (-8125 3200);
DISPLAY INVISIBLE (-8125 3200);
FORCEPROP 2 LAST CDS_SEC 1
J 0
(-8125 3200);
DISPLAY 1.021277 (-8125 3200);
DISPLAY INVISIBLE (-8125 3200);
FORCEPROP 1 LASTPIN (-8175 3100) $PN 1
J 0
(-8165 3080);
DISPLAY 0.489362 (-8165 3080);
FORCEPROP 1 LASTPIN (-8175 2900) $PN 2
J 0
(-8165 2880);
DISPLAY 0.489362 (-8165 2880);
FORCEPROP 1 LAST MATERIAL X6S
J 0
(-8125 2900);
DISPLAY 0.489362 (-8125 2900);
PAINT SKYBLUE (-8125 2900);
FORCEPROP 1 LAST TOLERANCE 20%
J 0
(-8125 2950);
DISPLAY 0.489362 (-8125 2950);
PAINT SKYBLUE (-8125 2950);
FORCEPROP 1 LAST VALUE 22UF
J 0
(-8125 3050);
DISPLAY 0.489362 (-8125 3050);
PAINT SKYBLUE (-8125 3050);
FORCEPROP 1 LAST VOLTAGE 4V
J 0
(-8125 3000);
DISPLAY 0.489362 (-8125 3000);
PAINT SKYBLUE (-8125 3000);
FORCEPROP 1 LAST PACK_TYPE C0402
J 0
(-8125 2800);
DISPLAY 0.489362 (-8125 2800);
PAINT SKYBLUE (-8125 2800);
FORCEPROP 2 LAST CDS_LIB pure_quanta
J 0
(-8175 3000);
PAINT MONO (-8175 3000);
DISPLAY INVISIBLE (-8175 3000);
FORCEPROP 1 LAST PATH I37
J 0
(-8125 3150);
DISPLAY 0.978723 (-8125 3150);
PAINT WHITE (-8125 3150);
DISPLAY INVISIBLE (-8125 3150);
FORCEPROP 1 LAST PART_NUMBER CH622KMEB02
J 0
(-8125 2850);
DISPLAY 0.489362 (-8125 2850);
PAINT SKYBLUE (-8125 2850);
DISPLAY INVISIBLE (-8125 2850);
FORCEADD Q_CAP..1
(-7725 2300);
FORCEPROP 1 LAST LOCATION C2553
J 0
(-7675 2400);
DISPLAY 0.489362 (-7675 2400);
PAINT SKYBLUE (-7675 2400);
FORCEPROP 2 LAST $SEC 1
J 0
(-7675 2500);
DISPLAY 0.680851 (-7675 2500);
PAINT MONO (-7675 2500);
DISPLAY INVISIBLE (-7675 2500);
FORCEPROP 2 LAST CDS_SEC 1
J 0
(-7675 2500);
DISPLAY 1.021277 (-7675 2500);
DISPLAY INVISIBLE (-7675 2500);
FORCEPROP 1 LASTPIN (-7725 2400) $PN 1
J 0
(-7715 2380);
DISPLAY 0.489362 (-7715 2380);
FORCEPROP 1 LASTPIN (-7725 2200) $PN 2
J 0
(-7715 2180);
DISPLAY 0.489362 (-7715 2180);
FORCEPROP 1 LAST MATERIAL X6S
J 0
(-7675 2200);
DISPLAY 0.489362 (-7675 2200);
PAINT SKYBLUE (-7675 2200);
FORCEPROP 1 LAST TOLERANCE 20%
J 0
(-7675 2250);
DISPLAY 0.489362 (-7675 2250);
PAINT SKYBLUE (-7675 2250);
FORCEPROP 1 LAST VALUE 22UF
J 0
(-7675 2350);
DISPLAY 0.489362 (-7675 2350);
PAINT SKYBLUE (-7675 2350);
FORCEPROP 1 LAST VOLTAGE 4V
J 0
(-7675 2300);
DISPLAY 0.489362 (-7675 2300);
PAINT SKYBLUE (-7675 2300);
FORCEPROP 1 LAST PACK_TYPE C0402
J 0
(-7675 2100);
DISPLAY 0.489362 (-7675 2100);
PAINT SKYBLUE (-7675 2100);
FORCEPROP 2 LAST CDS_LIB pure_quanta
J 0
(-7725 2300);
PAINT MONO (-7725 2300);
DISPLAY INVISIBLE (-7725 2300);
FORCEPROP 1 LAST PATH I38
J 0
(-7675 2450);
DISPLAY 0.978723 (-7675 2450);
PAINT WHITE (-7675 2450);
DISPLAY INVISIBLE (-7675 2450);
FORCEPROP 1 LAST PART_NUMBER CH622KMEB02
J 0
(-7675 2150);
DISPLAY 0.489362 (-7675 2150);
PAINT SKYBLUE (-7675 2150);
DISPLAY INVISIBLE (-7675 2150);
FORCEADD Q_CAP..1
(-7275 2300);
FORCEPROP 1 LAST LOCATION C2560
J 0
(-7225 2400);
DISPLAY 0.489362 (-7225 2400);
PAINT SKYBLUE (-7225 2400);
FORCEPROP 2 LAST $SEC 1
J 0
(-7225 2500);
DISPLAY 0.680851 (-7225 2500);
PAINT MONO (-7225 2500);
DISPLAY INVISIBLE (-7225 2500);
FORCEPROP 2 LAST CDS_SEC 1
J 0
(-7225 2500);
DISPLAY 1.021277 (-7225 2500);
DISPLAY INVISIBLE (-7225 2500);
FORCEPROP 1 LASTPIN (-7275 2400) $PN 1
J 0
(-7265 2380);
DISPLAY 0.489362 (-7265 2380);
FORCEPROP 1 LASTPIN (-7275 2200) $PN 2
J 0
(-7265 2180);
DISPLAY 0.489362 (-7265 2180);
FORCEPROP 1 LAST MATERIAL X6S
J 0
(-7225 2200);
DISPLAY 0.489362 (-7225 2200);
PAINT SKYBLUE (-7225 2200);
FORCEPROP 1 LAST TOLERANCE 20%
J 0
(-7225 2250);
DISPLAY 0.489362 (-7225 2250);
PAINT SKYBLUE (-7225 2250);
FORCEPROP 1 LAST VALUE 22UF
J 0
(-7225 2350);
DISPLAY 0.489362 (-7225 2350);
PAINT SKYBLUE (-7225 2350);
FORCEPROP 1 LAST VOLTAGE 4V
J 0
(-7225 2300);
DISPLAY 0.489362 (-7225 2300);
PAINT SKYBLUE (-7225 2300);
FORCEPROP 1 LAST PACK_TYPE C0402
J 0
(-7225 2100);
DISPLAY 0.489362 (-7225 2100);
PAINT SKYBLUE (-7225 2100);
FORCEPROP 2 LAST CDS_LIB pure_quanta
J 0
(-7275 2300);
PAINT MONO (-7275 2300);
DISPLAY INVISIBLE (-7275 2300);
FORCEPROP 1 LAST PATH I39
J 0
(-7225 2450);
DISPLAY 0.978723 (-7225 2450);
PAINT WHITE (-7225 2450);
DISPLAY INVISIBLE (-7225 2450);
FORCEPROP 1 LAST PART_NUMBER CH622KMEB02
J 0
(-7225 2150);
DISPLAY 0.489362 (-7225 2150);
PAINT SKYBLUE (-7225 2150);
DISPLAY INVISIBLE (-7225 2150);
FORCEADD Q_CAP..1
(-9075 1575);
FORCEPROP 1 LAST LOCATION C2533
J 0
(-9025 1675);
DISPLAY 0.489362 (-9025 1675);
PAINT SKYBLUE (-9025 1675);
FORCEPROP 2 LAST $SEC 1
J 0
(-9025 1775);
DISPLAY 0.680851 (-9025 1775);
PAINT MONO (-9025 1775);
DISPLAY INVISIBLE (-9025 1775);
FORCEPROP 2 LAST CDS_SEC 1
J 0
(-9025 1775);
DISPLAY 1.021277 (-9025 1775);
DISPLAY INVISIBLE (-9025 1775);
FORCEPROP 1 LASTPIN (-9075 1675) $PN 1
J 0
(-9065 1655);
DISPLAY 0.489362 (-9065 1655);
FORCEPROP 1 LASTPIN (-9075 1475) $PN 2
J 0
(-9065 1455);
DISPLAY 0.489362 (-9065 1455);
FORCEPROP 1 LAST MATERIAL X6S
J 0
(-9025 1475);
DISPLAY 0.489362 (-9025 1475);
PAINT SKYBLUE (-9025 1475);
FORCEPROP 1 LAST TOLERANCE 20%
J 0
(-9025 1525);
DISPLAY 0.489362 (-9025 1525);
PAINT SKYBLUE (-9025 1525);
FORCEPROP 1 LAST VALUE 22UF
J 0
(-9025 1625);
DISPLAY 0.489362 (-9025 1625);
PAINT SKYBLUE (-9025 1625);
FORCEPROP 1 LAST VOLTAGE 4V
J 0
(-9025 1575);
DISPLAY 0.489362 (-9025 1575);
PAINT SKYBLUE (-9025 1575);
FORCEPROP 1 LAST PACK_TYPE C0402
J 0
(-9025 1375);
DISPLAY 0.489362 (-9025 1375);
PAINT SKYBLUE (-9025 1375);
FORCEPROP 2 LAST CDS_LIB pure_quanta
J 0
(-9075 1575);
PAINT MONO (-9075 1575);
DISPLAY INVISIBLE (-9075 1575);
FORCEPROP 1 LAST PATH I4
J 0
(-9025 1725);
DISPLAY 0.978723 (-9025 1725);
PAINT WHITE (-9025 1725);
DISPLAY INVISIBLE (-9025 1725);
FORCEPROP 1 LAST PART_NUMBER CH622KMEB02
J 0
(-9025 1425);
DISPLAY 0.489362 (-9025 1425);
PAINT SKYBLUE (-9025 1425);
DISPLAY INVISIBLE (-9025 1425);
FORCEADD Q_CAP..1
(-7725 3000);
FORCEPROP 1 LAST LOCATION C2552
J 0
(-7675 3100);
DISPLAY 0.489362 (-7675 3100);
PAINT SKYBLUE (-7675 3100);
FORCEPROP 2 LAST $SEC 1
J 0
(-7675 3200);
DISPLAY 0.680851 (-7675 3200);
PAINT MONO (-7675 3200);
DISPLAY INVISIBLE (-7675 3200);
FORCEPROP 2 LAST CDS_SEC 1
J 0
(-7675 3200);
DISPLAY 1.021277 (-7675 3200);
DISPLAY INVISIBLE (-7675 3200);
FORCEPROP 1 LASTPIN (-7725 3100) $PN 1
J 0
(-7715 3080);
DISPLAY 0.489362 (-7715 3080);
FORCEPROP 1 LASTPIN (-7725 2900) $PN 2
J 0
(-7715 2880);
DISPLAY 0.489362 (-7715 2880);
FORCEPROP 1 LAST MATERIAL X6S
J 0
(-7675 2900);
DISPLAY 0.489362 (-7675 2900);
PAINT SKYBLUE (-7675 2900);
FORCEPROP 1 LAST TOLERANCE 20%
J 0
(-7675 2950);
DISPLAY 0.489362 (-7675 2950);
PAINT SKYBLUE (-7675 2950);
FORCEPROP 1 LAST VALUE 22UF
J 0
(-7675 3050);
DISPLAY 0.489362 (-7675 3050);
PAINT SKYBLUE (-7675 3050);
FORCEPROP 1 LAST VOLTAGE 4V
J 0
(-7675 3000);
DISPLAY 0.489362 (-7675 3000);
PAINT SKYBLUE (-7675 3000);
FORCEPROP 1 LAST PACK_TYPE C0402
J 0
(-7675 2800);
DISPLAY 0.489362 (-7675 2800);
PAINT SKYBLUE (-7675 2800);
FORCEPROP 2 LAST CDS_LIB pure_quanta
J 0
(-7725 3000);
PAINT MONO (-7725 3000);
DISPLAY INVISIBLE (-7725 3000);
FORCEPROP 1 LAST PATH I40
J 0
(-7675 3150);
DISPLAY 0.978723 (-7675 3150);
PAINT WHITE (-7675 3150);
DISPLAY INVISIBLE (-7675 3150);
FORCEPROP 1 LAST PART_NUMBER CH622KMEB02
J 0
(-7675 2850);
DISPLAY 0.489362 (-7675 2850);
PAINT SKYBLUE (-7675 2850);
DISPLAY INVISIBLE (-7675 2850);
FORCEADD Q_CAP..1
(-7275 3000);
FORCEPROP 1 LAST LOCATION C2559
J 0
(-7225 3100);
DISPLAY 0.489362 (-7225 3100);
PAINT SKYBLUE (-7225 3100);
FORCEPROP 2 LAST $SEC 1
J 0
(-7225 3200);
DISPLAY 0.680851 (-7225 3200);
PAINT MONO (-7225 3200);
DISPLAY INVISIBLE (-7225 3200);
FORCEPROP 2 LAST CDS_SEC 1
J 0
(-7225 3200);
DISPLAY 1.021277 (-7225 3200);
DISPLAY INVISIBLE (-7225 3200);
FORCEPROP 1 LASTPIN (-7275 3100) $PN 1
J 0
(-7265 3080);
DISPLAY 0.489362 (-7265 3080);
FORCEPROP 1 LASTPIN (-7275 2900) $PN 2
J 0
(-7265 2880);
DISPLAY 0.489362 (-7265 2880);
FORCEPROP 1 LAST MATERIAL X6S
J 0
(-7225 2900);
DISPLAY 0.489362 (-7225 2900);
PAINT SKYBLUE (-7225 2900);
FORCEPROP 1 LAST TOLERANCE 20%
J 0
(-7225 2950);
DISPLAY 0.489362 (-7225 2950);
PAINT SKYBLUE (-7225 2950);
FORCEPROP 1 LAST VALUE 22UF
J 0
(-7225 3050);
DISPLAY 0.489362 (-7225 3050);
PAINT SKYBLUE (-7225 3050);
FORCEPROP 1 LAST VOLTAGE 4V
J 0
(-7225 3000);
DISPLAY 0.489362 (-7225 3000);
PAINT SKYBLUE (-7225 3000);
FORCEPROP 1 LAST PACK_TYPE C0402
J 0
(-7225 2800);
DISPLAY 0.489362 (-7225 2800);
PAINT SKYBLUE (-7225 2800);
FORCEPROP 2 LAST CDS_LIB pure_quanta
J 0
(-7275 3000);
PAINT MONO (-7275 3000);
DISPLAY INVISIBLE (-7275 3000);
FORCEPROP 1 LAST PATH I41
J 0
(-7225 3150);
DISPLAY 0.978723 (-7225 3150);
PAINT WHITE (-7225 3150);
DISPLAY INVISIBLE (-7225 3150);
FORCEPROP 1 LAST PART_NUMBER CH622KMEB02
J 0
(-7225 2850);
DISPLAY 0.489362 (-7225 2850);
PAINT SKYBLUE (-7225 2850);
DISPLAY INVISIBLE (-7225 2850);
FORCEADD Q_CAP..1
(-8175 3725);
FORCEPROP 1 LAST LOCATION C2544
J 0
(-8125 3825);
DISPLAY 0.489362 (-8125 3825);
PAINT SKYBLUE (-8125 3825);
FORCEPROP 2 LAST $SEC 1
J 0
(-8125 3925);
DISPLAY 0.680851 (-8125 3925);
PAINT MONO (-8125 3925);
DISPLAY INVISIBLE (-8125 3925);
FORCEPROP 2 LAST CDS_SEC 1
J 0
(-8125 3925);
DISPLAY 1.021277 (-8125 3925);
DISPLAY INVISIBLE (-8125 3925);
FORCEPROP 1 LASTPIN (-8175 3825) $PN 1
J 0
(-8165 3805);
DISPLAY 0.489362 (-8165 3805);
FORCEPROP 1 LASTPIN (-8175 3625) $PN 2
J 0
(-8165 3605);
DISPLAY 0.489362 (-8165 3605);
FORCEPROP 1 LAST MATERIAL X6S
J 0
(-8125 3625);
DISPLAY 0.489362 (-8125 3625);
PAINT SKYBLUE (-8125 3625);
FORCEPROP 1 LAST TOLERANCE 20%
J 0
(-8125 3675);
DISPLAY 0.489362 (-8125 3675);
PAINT SKYBLUE (-8125 3675);
FORCEPROP 1 LAST VALUE 22UF
J 0
(-8125 3775);
DISPLAY 0.489362 (-8125 3775);
PAINT SKYBLUE (-8125 3775);
FORCEPROP 1 LAST VOLTAGE 4V
J 0
(-8125 3725);
DISPLAY 0.489362 (-8125 3725);
PAINT SKYBLUE (-8125 3725);
FORCEPROP 1 LAST PACK_TYPE C0402
J 0
(-8125 3525);
DISPLAY 0.489362 (-8125 3525);
PAINT SKYBLUE (-8125 3525);
FORCEPROP 2 LAST CDS_LIB pure_quanta
J 0
(-8175 3725);
PAINT MONO (-8175 3725);
DISPLAY INVISIBLE (-8175 3725);
FORCEPROP 1 LAST PATH I42
J 0
(-8125 3875);
DISPLAY 0.978723 (-8125 3875);
PAINT WHITE (-8125 3875);
DISPLAY INVISIBLE (-8125 3875);
FORCEPROP 1 LAST PART_NUMBER CH622KMEB02
J 0
(-8125 3575);
DISPLAY 0.489362 (-8125 3575);
PAINT SKYBLUE (-8125 3575);
DISPLAY INVISIBLE (-8125 3575);
FORCEADD Q_CAP..1
(-7725 3725);
FORCEPROP 1 LAST LOCATION C2551
J 0
(-7675 3825);
DISPLAY 0.489362 (-7675 3825);
PAINT SKYBLUE (-7675 3825);
FORCEPROP 2 LAST $SEC 1
J 0
(-7675 3925);
DISPLAY 0.680851 (-7675 3925);
PAINT MONO (-7675 3925);
DISPLAY INVISIBLE (-7675 3925);
FORCEPROP 2 LAST CDS_SEC 1
J 0
(-7675 3925);
DISPLAY 1.021277 (-7675 3925);
DISPLAY INVISIBLE (-7675 3925);
FORCEPROP 1 LASTPIN (-7725 3825) $PN 1
J 0
(-7715 3805);
DISPLAY 0.489362 (-7715 3805);
FORCEPROP 1 LASTPIN (-7725 3625) $PN 2
J 0
(-7715 3605);
DISPLAY 0.489362 (-7715 3605);
FORCEPROP 1 LAST MATERIAL X6S
J 0
(-7675 3625);
DISPLAY 0.489362 (-7675 3625);
PAINT SKYBLUE (-7675 3625);
FORCEPROP 1 LAST TOLERANCE 20%
J 0
(-7675 3675);
DISPLAY 0.489362 (-7675 3675);
PAINT SKYBLUE (-7675 3675);
FORCEPROP 1 LAST VALUE 22UF
J 0
(-7675 3775);
DISPLAY 0.489362 (-7675 3775);
PAINT SKYBLUE (-7675 3775);
FORCEPROP 1 LAST VOLTAGE 4V
J 0
(-7675 3725);
DISPLAY 0.489362 (-7675 3725);
PAINT SKYBLUE (-7675 3725);
FORCEPROP 1 LAST PACK_TYPE C0402
J 0
(-7675 3525);
DISPLAY 0.489362 (-7675 3525);
PAINT SKYBLUE (-7675 3525);
FORCEPROP 2 LAST CDS_LIB pure_quanta
J 0
(-7725 3725);
PAINT MONO (-7725 3725);
DISPLAY INVISIBLE (-7725 3725);
FORCEPROP 1 LAST PATH I43
J 0
(-7675 3875);
DISPLAY 0.978723 (-7675 3875);
PAINT WHITE (-7675 3875);
DISPLAY INVISIBLE (-7675 3875);
FORCEPROP 1 LAST PART_NUMBER CH622KMEB02
J 0
(-7675 3575);
DISPLAY 0.489362 (-7675 3575);
PAINT SKYBLUE (-7675 3575);
DISPLAY INVISIBLE (-7675 3575);
FORCEADD Q_CAP..1
(-7275 3725);
FORCEPROP 1 LAST LOCATION C2558
J 0
(-7225 3825);
DISPLAY 0.489362 (-7225 3825);
PAINT SKYBLUE (-7225 3825);
FORCEPROP 2 LAST $SEC 1
J 0
(-7225 3925);
DISPLAY 0.680851 (-7225 3925);
PAINT MONO (-7225 3925);
DISPLAY INVISIBLE (-7225 3925);
FORCEPROP 2 LAST CDS_SEC 1
J 0
(-7225 3925);
DISPLAY 1.021277 (-7225 3925);
DISPLAY INVISIBLE (-7225 3925);
FORCEPROP 1 LASTPIN (-7275 3825) $PN 1
J 0
(-7265 3805);
DISPLAY 0.489362 (-7265 3805);
FORCEPROP 1 LASTPIN (-7275 3625) $PN 2
J 0
(-7265 3605);
DISPLAY 0.489362 (-7265 3605);
FORCEPROP 1 LAST MATERIAL X6S
J 0
(-7225 3625);
DISPLAY 0.489362 (-7225 3625);
PAINT SKYBLUE (-7225 3625);
FORCEPROP 1 LAST TOLERANCE 20%
J 0
(-7225 3675);
DISPLAY 0.489362 (-7225 3675);
PAINT SKYBLUE (-7225 3675);
FORCEPROP 1 LAST VALUE 22UF
J 0
(-7225 3775);
DISPLAY 0.489362 (-7225 3775);
PAINT SKYBLUE (-7225 3775);
FORCEPROP 1 LAST VOLTAGE 4V
J 0
(-7225 3725);
DISPLAY 0.489362 (-7225 3725);
PAINT SKYBLUE (-7225 3725);
FORCEPROP 1 LAST PACK_TYPE C0402
J 0
(-7225 3525);
DISPLAY 0.489362 (-7225 3525);
PAINT SKYBLUE (-7225 3525);
FORCEPROP 2 LAST CDS_LIB pure_quanta
J 0
(-7275 3725);
PAINT MONO (-7275 3725);
DISPLAY INVISIBLE (-7275 3725);
FORCEPROP 1 LAST PATH I44
J 0
(-7225 3875);
DISPLAY 0.978723 (-7225 3875);
PAINT WHITE (-7225 3875);
DISPLAY INVISIBLE (-7225 3875);
FORCEPROP 1 LAST PART_NUMBER CH622KMEB02
J 0
(-7225 3575);
DISPLAY 0.489362 (-7225 3575);
PAINT SKYBLUE (-7225 3575);
DISPLAY INVISIBLE (-7225 3575);
FORCEADD Q_CAP..1
(-6825 2300);
FORCEPROP 1 LAST LOCATION C2567
J 0
(-6775 2400);
DISPLAY 0.489362 (-6775 2400);
PAINT SKYBLUE (-6775 2400);
FORCEPROP 2 LAST $SEC 1
J 0
(-6775 2500);
DISPLAY 0.680851 (-6775 2500);
PAINT MONO (-6775 2500);
DISPLAY INVISIBLE (-6775 2500);
FORCEPROP 2 LAST CDS_SEC 1
J 0
(-6775 2500);
DISPLAY 1.021277 (-6775 2500);
DISPLAY INVISIBLE (-6775 2500);
FORCEPROP 1 LASTPIN (-6825 2400) $PN 1
J 0
(-6815 2380);
DISPLAY 0.489362 (-6815 2380);
FORCEPROP 1 LASTPIN (-6825 2200) $PN 2
J 0
(-6815 2180);
DISPLAY 0.489362 (-6815 2180);
FORCEPROP 1 LAST MATERIAL X6S
J 0
(-6775 2200);
DISPLAY 0.489362 (-6775 2200);
PAINT SKYBLUE (-6775 2200);
FORCEPROP 1 LAST TOLERANCE 20%
J 0
(-6775 2250);
DISPLAY 0.489362 (-6775 2250);
PAINT SKYBLUE (-6775 2250);
FORCEPROP 1 LAST VALUE 22UF
J 0
(-6775 2350);
DISPLAY 0.489362 (-6775 2350);
PAINT SKYBLUE (-6775 2350);
FORCEPROP 1 LAST VOLTAGE 4V
J 0
(-6775 2300);
DISPLAY 0.489362 (-6775 2300);
PAINT SKYBLUE (-6775 2300);
FORCEPROP 1 LAST PACK_TYPE C0402
J 0
(-6775 2100);
DISPLAY 0.489362 (-6775 2100);
PAINT SKYBLUE (-6775 2100);
FORCEPROP 2 LAST CDS_LIB pure_quanta
J 0
(-6825 2300);
PAINT MONO (-6825 2300);
DISPLAY INVISIBLE (-6825 2300);
FORCEPROP 1 LAST PATH I45
J 0
(-6775 2450);
DISPLAY 0.978723 (-6775 2450);
PAINT WHITE (-6775 2450);
DISPLAY INVISIBLE (-6775 2450);
FORCEPROP 1 LAST PART_NUMBER CH622KMEB02
J 0
(-6775 2150);
DISPLAY 0.489362 (-6775 2150);
PAINT SKYBLUE (-6775 2150);
DISPLAY INVISIBLE (-6775 2150);
FORCEADD Q_CAP..1
(-6825 3000);
FORCEPROP 1 LAST LOCATION C2566
J 0
(-6775 3100);
DISPLAY 0.489362 (-6775 3100);
PAINT SKYBLUE (-6775 3100);
FORCEPROP 2 LAST $SEC 1
J 0
(-6775 3200);
DISPLAY 0.680851 (-6775 3200);
PAINT MONO (-6775 3200);
DISPLAY INVISIBLE (-6775 3200);
FORCEPROP 2 LAST CDS_SEC 1
J 0
(-6775 3200);
DISPLAY 1.021277 (-6775 3200);
DISPLAY INVISIBLE (-6775 3200);
FORCEPROP 1 LASTPIN (-6825 3100) $PN 1
J 0
(-6815 3080);
DISPLAY 0.489362 (-6815 3080);
FORCEPROP 1 LASTPIN (-6825 2900) $PN 2
J 0
(-6815 2880);
DISPLAY 0.489362 (-6815 2880);
FORCEPROP 1 LAST MATERIAL X6S
J 0
(-6775 2900);
DISPLAY 0.489362 (-6775 2900);
PAINT SKYBLUE (-6775 2900);
FORCEPROP 1 LAST TOLERANCE 20%
J 0
(-6775 2950);
DISPLAY 0.489362 (-6775 2950);
PAINT SKYBLUE (-6775 2950);
FORCEPROP 1 LAST VALUE 22UF
J 0
(-6775 3050);
DISPLAY 0.489362 (-6775 3050);
PAINT SKYBLUE (-6775 3050);
FORCEPROP 1 LAST VOLTAGE 4V
J 0
(-6775 3000);
DISPLAY 0.489362 (-6775 3000);
PAINT SKYBLUE (-6775 3000);
FORCEPROP 1 LAST PACK_TYPE C0402
J 0
(-6775 2800);
DISPLAY 0.489362 (-6775 2800);
PAINT SKYBLUE (-6775 2800);
FORCEPROP 2 LAST CDS_LIB pure_quanta
J 0
(-6825 3000);
PAINT MONO (-6825 3000);
DISPLAY INVISIBLE (-6825 3000);
FORCEPROP 1 LAST PATH I46
J 0
(-6775 3150);
DISPLAY 0.978723 (-6775 3150);
PAINT WHITE (-6775 3150);
DISPLAY INVISIBLE (-6775 3150);
FORCEPROP 1 LAST PART_NUMBER CH622KMEB02
J 0
(-6775 2850);
DISPLAY 0.489362 (-6775 2850);
PAINT SKYBLUE (-6775 2850);
DISPLAY INVISIBLE (-6775 2850);
FORCEADD Q_CAP..1
(-6375 2300);
FORCEPROP 1 LAST LOCATION C2574
J 0
(-6325 2400);
DISPLAY 0.489362 (-6325 2400);
PAINT SKYBLUE (-6325 2400);
FORCEPROP 2 LAST $SEC 1
J 0
(-6325 2500);
DISPLAY 0.680851 (-6325 2500);
PAINT MONO (-6325 2500);
DISPLAY INVISIBLE (-6325 2500);
FORCEPROP 2 LAST CDS_SEC 1
J 0
(-6325 2500);
DISPLAY 1.021277 (-6325 2500);
DISPLAY INVISIBLE (-6325 2500);
FORCEPROP 1 LASTPIN (-6375 2400) $PN 1
J 0
(-6365 2380);
DISPLAY 0.489362 (-6365 2380);
FORCEPROP 1 LASTPIN (-6375 2200) $PN 2
J 0
(-6365 2180);
DISPLAY 0.489362 (-6365 2180);
FORCEPROP 1 LAST MATERIAL X6S
J 0
(-6325 2200);
DISPLAY 0.489362 (-6325 2200);
PAINT SKYBLUE (-6325 2200);
FORCEPROP 1 LAST TOLERANCE 20%
J 0
(-6325 2250);
DISPLAY 0.489362 (-6325 2250);
PAINT SKYBLUE (-6325 2250);
FORCEPROP 1 LAST VALUE 22UF
J 0
(-6325 2350);
DISPLAY 0.489362 (-6325 2350);
PAINT SKYBLUE (-6325 2350);
FORCEPROP 1 LAST VOLTAGE 4V
J 0
(-6325 2300);
DISPLAY 0.489362 (-6325 2300);
PAINT SKYBLUE (-6325 2300);
FORCEPROP 1 LAST PACK_TYPE C0402
J 0
(-6325 2100);
DISPLAY 0.489362 (-6325 2100);
PAINT SKYBLUE (-6325 2100);
FORCEPROP 2 LAST CDS_LIB pure_quanta
J 0
(-6375 2300);
PAINT MONO (-6375 2300);
DISPLAY INVISIBLE (-6375 2300);
FORCEPROP 1 LAST PATH I47
J 0
(-6325 2450);
DISPLAY 0.978723 (-6325 2450);
PAINT WHITE (-6325 2450);
DISPLAY INVISIBLE (-6325 2450);
FORCEPROP 1 LAST PART_NUMBER CH622KMEB02
J 0
(-6325 2150);
DISPLAY 0.489362 (-6325 2150);
PAINT SKYBLUE (-6325 2150);
DISPLAY INVISIBLE (-6325 2150);
FORCEADD Q_CAP..1
(-6375 3000);
FORCEPROP 1 LAST LOCATION C2573
J 0
(-6325 3100);
DISPLAY 0.489362 (-6325 3100);
PAINT SKYBLUE (-6325 3100);
FORCEPROP 2 LAST $SEC 1
J 0
(-6325 3200);
DISPLAY 0.680851 (-6325 3200);
PAINT MONO (-6325 3200);
DISPLAY INVISIBLE (-6325 3200);
FORCEPROP 2 LAST CDS_SEC 1
J 0
(-6325 3200);
DISPLAY 1.021277 (-6325 3200);
DISPLAY INVISIBLE (-6325 3200);
FORCEPROP 1 LASTPIN (-6375 3100) $PN 1
J 0
(-6365 3080);
DISPLAY 0.489362 (-6365 3080);
FORCEPROP 1 LASTPIN (-6375 2900) $PN 2
J 0
(-6365 2880);
DISPLAY 0.489362 (-6365 2880);
FORCEPROP 1 LAST MATERIAL X6S
J 0
(-6325 2900);
DISPLAY 0.489362 (-6325 2900);
PAINT SKYBLUE (-6325 2900);
FORCEPROP 1 LAST TOLERANCE 20%
J 0
(-6325 2950);
DISPLAY 0.489362 (-6325 2950);
PAINT SKYBLUE (-6325 2950);
FORCEPROP 1 LAST VALUE 22UF
J 0
(-6325 3050);
DISPLAY 0.489362 (-6325 3050);
PAINT SKYBLUE (-6325 3050);
FORCEPROP 1 LAST VOLTAGE 4V
J 0
(-6325 3000);
DISPLAY 0.489362 (-6325 3000);
PAINT SKYBLUE (-6325 3000);
FORCEPROP 1 LAST PACK_TYPE C0402
J 0
(-6325 2800);
DISPLAY 0.489362 (-6325 2800);
PAINT SKYBLUE (-6325 2800);
FORCEPROP 2 LAST CDS_LIB pure_quanta
J 0
(-6375 3000);
PAINT MONO (-6375 3000);
DISPLAY INVISIBLE (-6375 3000);
FORCEPROP 1 LAST PATH I48
J 0
(-6325 3150);
DISPLAY 0.978723 (-6325 3150);
PAINT WHITE (-6325 3150);
DISPLAY INVISIBLE (-6325 3150);
FORCEPROP 1 LAST PART_NUMBER CH622KMEB02
J 0
(-6325 2850);
DISPLAY 0.489362 (-6325 2850);
PAINT SKYBLUE (-6325 2850);
DISPLAY INVISIBLE (-6325 2850);
FORCEADD Q_CAP..1
(-6825 3725);
FORCEPROP 1 LAST LOCATION C2565
J 0
(-6775 3825);
DISPLAY 0.489362 (-6775 3825);
PAINT SKYBLUE (-6775 3825);
FORCEPROP 2 LAST $SEC 1
J 0
(-6775 3925);
DISPLAY 0.680851 (-6775 3925);
PAINT MONO (-6775 3925);
DISPLAY INVISIBLE (-6775 3925);
FORCEPROP 2 LAST CDS_SEC 1
J 0
(-6775 3925);
DISPLAY 1.021277 (-6775 3925);
DISPLAY INVISIBLE (-6775 3925);
FORCEPROP 1 LASTPIN (-6825 3825) $PN 1
J 0
(-6815 3805);
DISPLAY 0.489362 (-6815 3805);
FORCEPROP 1 LASTPIN (-6825 3625) $PN 2
J 0
(-6815 3605);
DISPLAY 0.489362 (-6815 3605);
FORCEPROP 1 LAST MATERIAL X6S
J 0
(-6775 3625);
DISPLAY 0.489362 (-6775 3625);
PAINT SKYBLUE (-6775 3625);
FORCEPROP 1 LAST TOLERANCE 20%
J 0
(-6775 3675);
DISPLAY 0.489362 (-6775 3675);
PAINT SKYBLUE (-6775 3675);
FORCEPROP 1 LAST VALUE 22UF
J 0
(-6775 3775);
DISPLAY 0.489362 (-6775 3775);
PAINT SKYBLUE (-6775 3775);
FORCEPROP 1 LAST VOLTAGE 4V
J 0
(-6775 3725);
DISPLAY 0.489362 (-6775 3725);
PAINT SKYBLUE (-6775 3725);
FORCEPROP 1 LAST PACK_TYPE C0402
J 0
(-6775 3525);
DISPLAY 0.489362 (-6775 3525);
PAINT SKYBLUE (-6775 3525);
FORCEPROP 2 LAST CDS_LIB pure_quanta
J 0
(-6825 3725);
PAINT MONO (-6825 3725);
DISPLAY INVISIBLE (-6825 3725);
FORCEPROP 1 LAST PATH I49
J 0
(-6775 3875);
DISPLAY 0.978723 (-6775 3875);
PAINT WHITE (-6775 3875);
DISPLAY INVISIBLE (-6775 3875);
FORCEPROP 1 LAST PART_NUMBER CH622KMEB02
J 0
(-6775 3575);
DISPLAY 0.489362 (-6775 3575);
PAINT SKYBLUE (-6775 3575);
DISPLAY INVISIBLE (-6775 3575);
FORCEADD UNIVERSAL_POWER..1
(-9075 1850);
FORCEPROP 3 LASTPIN (-9075 1800) SIG_NAME PVDDCR_SOC_P0\g
J 0
(-9065 1810);
DISPLAY 0.659574 (-9065 1810);
PAINT MONO (-9065 1810);
DISPLAY INVISIBLE (-9065 1810);
FORCEPROP 1 LAST HDL_POWER PVDDCR_SOC_P0
J 1
(-9075 1900);
DISPLAY 0.489362 (-9075 1900);
PAINT GREEN (-9075 1900);
FORCEPROP 2 LAST CDS_LIB pure_quanta_power
J 0
(-9075 1850);
DISPLAY INVISIBLE (-9075 1850);
FORCEPROP 1 LAST PATH I5
J 0
(-9025 1875);
DISPLAY 0.872340 (-9025 1875);
PAINT AQUA (-9025 1875);
DISPLAY INVISIBLE (-9025 1875);
FORCEADD Q_CAP..1
(-6375 3725);
FORCEPROP 1 LAST LOCATION C2572
J 0
(-6325 3825);
DISPLAY 0.489362 (-6325 3825);
PAINT SKYBLUE (-6325 3825);
FORCEPROP 2 LAST $SEC 1
J 0
(-6325 3925);
DISPLAY 0.680851 (-6325 3925);
PAINT MONO (-6325 3925);
DISPLAY INVISIBLE (-6325 3925);
FORCEPROP 2 LAST CDS_SEC 1
J 0
(-6325 3925);
DISPLAY 1.021277 (-6325 3925);
DISPLAY INVISIBLE (-6325 3925);
FORCEPROP 1 LASTPIN (-6375 3825) $PN 1
J 0
(-6365 3805);
DISPLAY 0.489362 (-6365 3805);
FORCEPROP 1 LASTPIN (-6375 3625) $PN 2
J 0
(-6365 3605);
DISPLAY 0.489362 (-6365 3605);
FORCEPROP 1 LAST MATERIAL X6S
J 0
(-6325 3625);
DISPLAY 0.489362 (-6325 3625);
PAINT SKYBLUE (-6325 3625);
FORCEPROP 1 LAST TOLERANCE 20%
J 0
(-6325 3675);
DISPLAY 0.489362 (-6325 3675);
PAINT SKYBLUE (-6325 3675);
FORCEPROP 1 LAST VALUE 22UF
J 0
(-6325 3775);
DISPLAY 0.489362 (-6325 3775);
PAINT SKYBLUE (-6325 3775);
FORCEPROP 1 LAST VOLTAGE 4V
J 0
(-6325 3725);
DISPLAY 0.489362 (-6325 3725);
PAINT SKYBLUE (-6325 3725);
FORCEPROP 1 LAST PACK_TYPE C0402
J 0
(-6325 3525);
DISPLAY 0.489362 (-6325 3525);
PAINT SKYBLUE (-6325 3525);
FORCEPROP 2 LAST CDS_LIB pure_quanta
J 0
(-6375 3725);
PAINT MONO (-6375 3725);
DISPLAY INVISIBLE (-6375 3725);
FORCEPROP 1 LAST PATH I50
J 0
(-6325 3875);
DISPLAY 0.978723 (-6325 3875);
PAINT WHITE (-6325 3875);
DISPLAY INVISIBLE (-6325 3875);
FORCEPROP 1 LAST PART_NUMBER CH622KMEB02
J 0
(-6325 3575);
DISPLAY 0.489362 (-6325 3575);
PAINT SKYBLUE (-6325 3575);
DISPLAY INVISIBLE (-6325 3575);
FORCEADD Q_CAP..1
(-5925 1575);
FORCEPROP 1 LAST LOCATION C2582
J 0
(-5875 1675);
DISPLAY 0.489362 (-5875 1675);
PAINT SKYBLUE (-5875 1675);
FORCEPROP 2 LAST $SEC 1
J 0
(-5875 1775);
DISPLAY 0.680851 (-5875 1775);
PAINT MONO (-5875 1775);
DISPLAY INVISIBLE (-5875 1775);
FORCEPROP 2 LAST CDS_SEC 1
J 0
(-5875 1775);
DISPLAY 1.021277 (-5875 1775);
DISPLAY INVISIBLE (-5875 1775);
FORCEPROP 1 LASTPIN (-5925 1675) $PN 1
J 0
(-5915 1655);
DISPLAY 0.489362 (-5915 1655);
FORCEPROP 1 LASTPIN (-5925 1475) $PN 2
J 0
(-5915 1455);
DISPLAY 0.489362 (-5915 1455);
FORCEPROP 1 LAST MATERIAL X6S
J 0
(-5875 1475);
DISPLAY 0.489362 (-5875 1475);
PAINT SKYBLUE (-5875 1475);
FORCEPROP 1 LAST TOLERANCE 20%
J 0
(-5875 1525);
DISPLAY 0.489362 (-5875 1525);
PAINT SKYBLUE (-5875 1525);
FORCEPROP 1 LAST VALUE 22UF
J 0
(-5875 1625);
DISPLAY 0.489362 (-5875 1625);
PAINT SKYBLUE (-5875 1625);
FORCEPROP 1 LAST VOLTAGE 4V
J 0
(-5875 1575);
DISPLAY 0.489362 (-5875 1575);
PAINT SKYBLUE (-5875 1575);
FORCEPROP 1 LAST PACK_TYPE C0402
J 0
(-5875 1375);
DISPLAY 0.489362 (-5875 1375);
PAINT SKYBLUE (-5875 1375);
FORCEPROP 2 LAST CDS_LIB pure_quanta
J 0
(-5925 1575);
PAINT MONO (-5925 1575);
DISPLAY INVISIBLE (-5925 1575);
FORCEPROP 1 LAST PATH I51
J 0
(-5875 1725);
DISPLAY 0.978723 (-5875 1725);
PAINT WHITE (-5875 1725);
DISPLAY INVISIBLE (-5875 1725);
FORCEPROP 1 LAST PART_NUMBER CH622KMEB02
J 0
(-5875 1425);
DISPLAY 0.489362 (-5875 1425);
PAINT SKYBLUE (-5875 1425);
DISPLAY INVISIBLE (-5875 1425);
FORCEADD Q_CAP..1
(-5475 1575);
FORCEPROP 1 LAST LOCATION C2589
J 0
(-5425 1675);
DISPLAY 0.489362 (-5425 1675);
PAINT SKYBLUE (-5425 1675);
FORCEPROP 2 LAST $SEC 1
J 0
(-5425 1775);
DISPLAY 0.680851 (-5425 1775);
PAINT MONO (-5425 1775);
DISPLAY INVISIBLE (-5425 1775);
FORCEPROP 2 LAST CDS_SEC 1
J 0
(-5425 1775);
DISPLAY 1.021277 (-5425 1775);
DISPLAY INVISIBLE (-5425 1775);
FORCEPROP 1 LASTPIN (-5475 1675) $PN 1
J 0
(-5465 1655);
DISPLAY 0.489362 (-5465 1655);
FORCEPROP 1 LASTPIN (-5475 1475) $PN 2
J 0
(-5465 1455);
DISPLAY 0.489362 (-5465 1455);
FORCEPROP 1 LAST MATERIAL X6S
J 0
(-5425 1475);
DISPLAY 0.489362 (-5425 1475);
PAINT SKYBLUE (-5425 1475);
FORCEPROP 1 LAST TOLERANCE 20%
J 0
(-5425 1525);
DISPLAY 0.489362 (-5425 1525);
PAINT SKYBLUE (-5425 1525);
FORCEPROP 1 LAST VALUE 22UF
J 0
(-5425 1625);
DISPLAY 0.489362 (-5425 1625);
PAINT SKYBLUE (-5425 1625);
FORCEPROP 1 LAST VOLTAGE 4V
J 0
(-5425 1575);
DISPLAY 0.489362 (-5425 1575);
PAINT SKYBLUE (-5425 1575);
FORCEPROP 1 LAST PACK_TYPE C0402
J 0
(-5425 1375);
DISPLAY 0.489362 (-5425 1375);
PAINT SKYBLUE (-5425 1375);
FORCEPROP 2 LAST CDS_LIB pure_quanta
J 0
(-5475 1575);
PAINT MONO (-5475 1575);
DISPLAY INVISIBLE (-5475 1575);
FORCEPROP 1 LAST PATH I52
J 0
(-5425 1725);
DISPLAY 0.978723 (-5425 1725);
PAINT WHITE (-5425 1725);
DISPLAY INVISIBLE (-5425 1725);
FORCEPROP 1 LAST PART_NUMBER CH622KMEB02
J 0
(-5425 1425);
DISPLAY 0.489362 (-5425 1425);
PAINT SKYBLUE (-5425 1425);
DISPLAY INVISIBLE (-5425 1425);
FORCEADD Q_CAP..1
(-4500 800);
FORCEPROP 1 LAST LOCATION C3932
J 0
(-4450 900);
DISPLAY 0.489362 (-4450 900);
PAINT SKYBLUE (-4450 900);
FORCEPROP 2 LAST $SEC 1
J 0
(-4450 1000);
DISPLAY 0.680851 (-4450 1000);
PAINT MONO (-4450 1000);
DISPLAY INVISIBLE (-4450 1000);
FORCEPROP 2 LAST CDS_SEC 1
J 0
(-4450 1000);
DISPLAY 1.021277 (-4450 1000);
DISPLAY INVISIBLE (-4450 1000);
FORCEPROP 1 LASTPIN (-4500 900) $PN 1
J 0
(-4490 880);
DISPLAY 0.489362 (-4490 880);
FORCEPROP 1 LASTPIN (-4500 700) $PN 2
J 0
(-4490 680);
DISPLAY 0.489362 (-4490 680);
FORCEPROP 1 LAST MATERIAL X6S
J 0
(-4450 700);
DISPLAY 0.489362 (-4450 700);
PAINT SKYBLUE (-4450 700);
FORCEPROP 1 LAST TOLERANCE 20%
J 0
(-4450 750);
DISPLAY 0.489362 (-4450 750);
PAINT SKYBLUE (-4450 750);
FORCEPROP 1 LAST VALUE 22UF
J 0
(-4450 850);
DISPLAY 0.489362 (-4450 850);
PAINT SKYBLUE (-4450 850);
FORCEPROP 1 LAST VOLTAGE 4V
J 0
(-4450 800);
DISPLAY 0.489362 (-4450 800);
PAINT SKYBLUE (-4450 800);
FORCEPROP 1 LAST PACK_TYPE C0402
J 0
(-4450 600);
DISPLAY 0.489362 (-4450 600);
PAINT SKYBLUE (-4450 600);
FORCEPROP 2 LAST CDS_LIB pure_quanta
J 0
(-4500 800);
PAINT MONO (-4500 800);
DISPLAY INVISIBLE (-4500 800);
FORCEPROP 1 LAST PATH I53
J 0
(-4450 950);
DISPLAY 0.978723 (-4450 950);
PAINT WHITE (-4450 950);
DISPLAY INVISIBLE (-4450 950);
FORCEPROP 1 LAST PART_NUMBER CH622KMEB02
J 0
(-4450 650);
DISPLAY 0.489362 (-4450 650);
PAINT SKYBLUE (-4450 650);
DISPLAY INVISIBLE (-4450 650);
FORCEADD UNIVERSAL_POWER..1
(-4500 1075);
FORCEPROP 3 LASTPIN (-4500 1025) SIG_NAME PVDD11_S3_P0\g
J 0
(-4490 1035);
DISPLAY 0.659574 (-4490 1035);
PAINT MONO (-4490 1035);
DISPLAY INVISIBLE (-4490 1035);
FORCEPROP 1 LAST HDL_POWER PVDD11_S3_P0
J 1
(-4500 1125);
DISPLAY 0.489362 (-4500 1125);
PAINT GREEN (-4500 1125);
FORCEPROP 2 LAST CDS_LIB pure_quanta_power
J 0
(-4500 1075);
DISPLAY INVISIBLE (-4500 1075);
FORCEPROP 1 LAST PATH I54
J 0
(-4450 1100);
DISPLAY 0.872340 (-4450 1100);
PAINT AQUA (-4450 1100);
DISPLAY INVISIBLE (-4450 1100);
FORCEADD UNIVERSAL_GND..1
(-5075 1200);
FORCEPROP 3 LASTPIN (-5075 1250) SIG_NAME GND\g
J 0
(-5065 1260);
DISPLAY 0.659574 (-5065 1260);
PAINT MONO (-5065 1260);
DISPLAY INVISIBLE (-5065 1260);
FORCEPROP 2 LAST CDS_LIB pure_quanta_power
J 0
(-5075 1200);
PAINT MONO (-5075 1200);
DISPLAY INVISIBLE (-5075 1200);
FORCEPROP 1 LAST HDL_POWER GND
J 1
(-5050 1125);
DISPLAY 0.872340 (-5050 1125);
PAINT GREEN (-5050 1125);
DISPLAY INVISIBLE (-5050 1125);
FORCEPROP 1 LAST PATH I55
J 0
(-5000 1200);
DISPLAY 0.872340 (-5000 1200);
PAINT AQUA (-5000 1200);
DISPLAY INVISIBLE (-5000 1200);
FORCEADD Q_CAP..1
(-5075 1575);
FORCEPROP 1 LAST LOCATION C2596
J 0
(-5025 1675);
DISPLAY 0.489362 (-5025 1675);
PAINT SKYBLUE (-5025 1675);
FORCEPROP 2 LAST $SEC 1
J 0
(-5025 1775);
DISPLAY 0.680851 (-5025 1775);
PAINT MONO (-5025 1775);
DISPLAY INVISIBLE (-5025 1775);
FORCEPROP 2 LAST CDS_SEC 1
J 0
(-5025 1775);
DISPLAY 1.021277 (-5025 1775);
DISPLAY INVISIBLE (-5025 1775);
FORCEPROP 1 LASTPIN (-5075 1675) $PN 1
J 0
(-5065 1655);
DISPLAY 0.489362 (-5065 1655);
FORCEPROP 1 LASTPIN (-5075 1475) $PN 2
J 0
(-5065 1455);
DISPLAY 0.489362 (-5065 1455);
FORCEPROP 1 LAST MATERIAL X6S
J 0
(-5025 1475);
DISPLAY 0.489362 (-5025 1475);
PAINT SKYBLUE (-5025 1475);
FORCEPROP 1 LAST TOLERANCE 20%
J 0
(-5025 1525);
DISPLAY 0.489362 (-5025 1525);
PAINT SKYBLUE (-5025 1525);
FORCEPROP 1 LAST VALUE 22UF
J 0
(-5025 1625);
DISPLAY 0.489362 (-5025 1625);
PAINT SKYBLUE (-5025 1625);
FORCEPROP 1 LAST VOLTAGE 4V
J 0
(-5025 1575);
DISPLAY 0.489362 (-5025 1575);
PAINT SKYBLUE (-5025 1575);
FORCEPROP 1 LAST PACK_TYPE C0402
J 0
(-5025 1375);
DISPLAY 0.489362 (-5025 1375);
PAINT SKYBLUE (-5025 1375);
FORCEPROP 2 LAST CDS_LIB pure_quanta
J 0
(-5075 1575);
PAINT MONO (-5075 1575);
DISPLAY INVISIBLE (-5075 1575);
FORCEPROP 1 LAST PATH I56
J 0
(-5025 1725);
DISPLAY 0.978723 (-5025 1725);
PAINT WHITE (-5025 1725);
DISPLAY INVISIBLE (-5025 1725);
FORCEPROP 1 LAST PART_NUMBER CH622KMEB02
J 0
(-5025 1425);
DISPLAY 0.489362 (-5025 1425);
PAINT SKYBLUE (-5025 1425);
DISPLAY INVISIBLE (-5025 1425);
FORCEADD UNIVERSAL_GND..1
(-5075 1925);
FORCEPROP 3 LASTPIN (-5075 1975) SIG_NAME GND\g
J 0
(-5065 1985);
DISPLAY 0.659574 (-5065 1985);
PAINT MONO (-5065 1985);
DISPLAY INVISIBLE (-5065 1985);
FORCEPROP 2 LAST CDS_LIB pure_quanta_power
J 0
(-5075 1925);
PAINT MONO (-5075 1925);
DISPLAY INVISIBLE (-5075 1925);
FORCEPROP 1 LAST HDL_POWER GND
J 1
(-5050 1850);
DISPLAY 0.872340 (-5050 1850);
PAINT GREEN (-5050 1850);
DISPLAY INVISIBLE (-5050 1850);
FORCEPROP 1 LAST PATH I57
J 0
(-5000 1925);
DISPLAY 0.872340 (-5000 1925);
PAINT AQUA (-5000 1925);
DISPLAY INVISIBLE (-5000 1925);
FORCEADD Q_CAP..1
(-4500 1400);
FORCEPROP 1 LAST LOCATION C2603
J 0
(-4450 1500);
DISPLAY 0.489362 (-4450 1500);
PAINT SKYBLUE (-4450 1500);
FORCEPROP 2 LAST $SEC 1
J 0
(-4450 1600);
DISPLAY 0.680851 (-4450 1600);
PAINT MONO (-4450 1600);
DISPLAY INVISIBLE (-4450 1600);
FORCEPROP 2 LAST CDS_SEC 1
J 0
(-4450 1600);
DISPLAY 1.021277 (-4450 1600);
DISPLAY INVISIBLE (-4450 1600);
FORCEPROP 1 LASTPIN (-4500 1500) $PN 1
J 0
(-4490 1480);
DISPLAY 0.489362 (-4490 1480);
FORCEPROP 1 LASTPIN (-4500 1300) $PN 2
J 0
(-4490 1280);
DISPLAY 0.489362 (-4490 1280);
FORCEPROP 1 LAST MATERIAL X6S
J 0
(-4450 1300);
DISPLAY 0.489362 (-4450 1300);
PAINT SKYBLUE (-4450 1300);
FORCEPROP 1 LAST TOLERANCE 20%
J 0
(-4450 1350);
DISPLAY 0.489362 (-4450 1350);
PAINT SKYBLUE (-4450 1350);
FORCEPROP 1 LAST VALUE 22UF
J 0
(-4450 1450);
DISPLAY 0.489362 (-4450 1450);
PAINT SKYBLUE (-4450 1450);
FORCEPROP 1 LAST VOLTAGE 4V
J 0
(-4450 1400);
DISPLAY 0.489362 (-4450 1400);
PAINT SKYBLUE (-4450 1400);
FORCEPROP 1 LAST PACK_TYPE C0402
J 0
(-4450 1200);
DISPLAY 0.489362 (-4450 1200);
PAINT SKYBLUE (-4450 1200);
FORCEPROP 2 LAST CDS_LIB pure_quanta
J 0
(-4500 1400);
PAINT MONO (-4500 1400);
DISPLAY INVISIBLE (-4500 1400);
FORCEPROP 1 LAST PATH I58
J 0
(-4450 1550);
DISPLAY 0.978723 (-4450 1550);
PAINT WHITE (-4450 1550);
DISPLAY INVISIBLE (-4450 1550);
FORCEPROP 1 LAST PART_NUMBER CH622KMEB02
J 0
(-4450 1250);
DISPLAY 0.489362 (-4450 1250);
PAINT SKYBLUE (-4450 1250);
DISPLAY INVISIBLE (-4450 1250);
FORCEADD UNIVERSAL_POWER..1
(-4500 1675);
FORCEPROP 3 LASTPIN (-4500 1625) SIG_NAME PVDD11_S3_P0\g
J 0
(-4490 1635);
DISPLAY 0.659574 (-4490 1635);
PAINT MONO (-4490 1635);
DISPLAY INVISIBLE (-4490 1635);
FORCEPROP 1 LAST HDL_POWER PVDD11_S3_P0
J 1
(-4500 1725);
DISPLAY 0.489362 (-4500 1725);
PAINT GREEN (-4500 1725);
FORCEPROP 2 LAST CDS_LIB pure_quanta_power
J 0
(-4500 1675);
DISPLAY INVISIBLE (-4500 1675);
FORCEPROP 1 LAST PATH I59
J 0
(-4450 1700);
DISPLAY 0.872340 (-4450 1700);
PAINT AQUA (-4450 1700);
DISPLAY INVISIBLE (-4450 1700);
FORCEADD Q_CAP..1
(-8625 1575);
FORCEPROP 1 LAST LOCATION C2540
J 0
(-8575 1675);
DISPLAY 0.489362 (-8575 1675);
PAINT SKYBLUE (-8575 1675);
FORCEPROP 2 LAST $SEC 1
J 0
(-8575 1775);
DISPLAY 0.680851 (-8575 1775);
PAINT MONO (-8575 1775);
DISPLAY INVISIBLE (-8575 1775);
FORCEPROP 2 LAST CDS_SEC 1
J 0
(-8575 1775);
DISPLAY 1.021277 (-8575 1775);
DISPLAY INVISIBLE (-8575 1775);
FORCEPROP 1 LASTPIN (-8625 1675) $PN 1
J 0
(-8615 1655);
DISPLAY 0.489362 (-8615 1655);
FORCEPROP 1 LASTPIN (-8625 1475) $PN 2
J 0
(-8615 1455);
DISPLAY 0.489362 (-8615 1455);
FORCEPROP 1 LAST MATERIAL X6S
J 0
(-8575 1475);
DISPLAY 0.489362 (-8575 1475);
PAINT SKYBLUE (-8575 1475);
FORCEPROP 1 LAST TOLERANCE 20%
J 0
(-8575 1525);
DISPLAY 0.489362 (-8575 1525);
PAINT SKYBLUE (-8575 1525);
FORCEPROP 1 LAST VALUE 22UF
J 0
(-8575 1625);
DISPLAY 0.489362 (-8575 1625);
PAINT SKYBLUE (-8575 1625);
FORCEPROP 1 LAST VOLTAGE 4V
J 0
(-8575 1575);
DISPLAY 0.489362 (-8575 1575);
PAINT SKYBLUE (-8575 1575);
FORCEPROP 1 LAST PACK_TYPE C0402
J 0
(-8575 1375);
DISPLAY 0.489362 (-8575 1375);
PAINT SKYBLUE (-8575 1375);
FORCEPROP 2 LAST CDS_LIB pure_quanta
J 0
(-8625 1575);
PAINT MONO (-8625 1575);
DISPLAY INVISIBLE (-8625 1575);
FORCEPROP 1 LAST PATH I6
J 0
(-8575 1725);
DISPLAY 0.978723 (-8575 1725);
PAINT WHITE (-8575 1725);
DISPLAY INVISIBLE (-8575 1725);
FORCEPROP 1 LAST PART_NUMBER CH622KMEB02
J 0
(-8575 1425);
DISPLAY 0.489362 (-8575 1425);
PAINT SKYBLUE (-8575 1425);
DISPLAY INVISIBLE (-8575 1425);
FORCEADD Q_CAP..1
(-4500 2000);
FORCEPROP 1 LAST LOCATION C2602
J 0
(-4450 2100);
DISPLAY 0.489362 (-4450 2100);
PAINT SKYBLUE (-4450 2100);
FORCEPROP 2 LAST $SEC 1
J 0
(-4450 2200);
DISPLAY 0.680851 (-4450 2200);
PAINT MONO (-4450 2200);
DISPLAY INVISIBLE (-4450 2200);
FORCEPROP 2 LAST CDS_SEC 1
J 0
(-4450 2200);
DISPLAY 1.021277 (-4450 2200);
DISPLAY INVISIBLE (-4450 2200);
FORCEPROP 1 LASTPIN (-4500 2100) $PN 1
J 0
(-4490 2080);
DISPLAY 0.489362 (-4490 2080);
FORCEPROP 1 LASTPIN (-4500 1900) $PN 2
J 0
(-4490 1880);
DISPLAY 0.489362 (-4490 1880);
FORCEPROP 1 LAST MATERIAL X6S
J 0
(-4450 1900);
DISPLAY 0.489362 (-4450 1900);
PAINT SKYBLUE (-4450 1900);
FORCEPROP 1 LAST TOLERANCE 20%
J 0
(-4450 1950);
DISPLAY 0.489362 (-4450 1950);
PAINT SKYBLUE (-4450 1950);
FORCEPROP 1 LAST VALUE 22UF
J 0
(-4450 2050);
DISPLAY 0.489362 (-4450 2050);
PAINT SKYBLUE (-4450 2050);
FORCEPROP 1 LAST VOLTAGE 4V
J 0
(-4450 2000);
DISPLAY 0.489362 (-4450 2000);
PAINT SKYBLUE (-4450 2000);
FORCEPROP 1 LAST PACK_TYPE C0402
J 0
(-4450 1800);
DISPLAY 0.489362 (-4450 1800);
PAINT SKYBLUE (-4450 1800);
FORCEPROP 2 LAST CDS_LIB pure_quanta
J 0
(-4500 2000);
PAINT MONO (-4500 2000);
DISPLAY INVISIBLE (-4500 2000);
FORCEPROP 1 LAST PATH I60
J 0
(-4450 2150);
DISPLAY 0.978723 (-4450 2150);
PAINT WHITE (-4450 2150);
DISPLAY INVISIBLE (-4450 2150);
FORCEPROP 1 LAST PART_NUMBER CH622KMEB02
J 0
(-4450 1850);
DISPLAY 0.489362 (-4450 1850);
PAINT SKYBLUE (-4450 1850);
DISPLAY INVISIBLE (-4450 1850);
FORCEADD Q_CAP..1
(-5925 2300);
FORCEPROP 1 LAST LOCATION C2581
J 0
(-5875 2400);
DISPLAY 0.489362 (-5875 2400);
PAINT SKYBLUE (-5875 2400);
FORCEPROP 2 LAST $SEC 1
J 0
(-5875 2500);
DISPLAY 0.680851 (-5875 2500);
PAINT MONO (-5875 2500);
DISPLAY INVISIBLE (-5875 2500);
FORCEPROP 2 LAST CDS_SEC 1
J 0
(-5875 2500);
DISPLAY 1.021277 (-5875 2500);
DISPLAY INVISIBLE (-5875 2500);
FORCEPROP 1 LASTPIN (-5925 2400) $PN 1
J 0
(-5915 2380);
DISPLAY 0.489362 (-5915 2380);
FORCEPROP 1 LASTPIN (-5925 2200) $PN 2
J 0
(-5915 2180);
DISPLAY 0.489362 (-5915 2180);
FORCEPROP 1 LAST MATERIAL X6S
J 0
(-5875 2200);
DISPLAY 0.489362 (-5875 2200);
PAINT SKYBLUE (-5875 2200);
FORCEPROP 1 LAST TOLERANCE 20%
J 0
(-5875 2250);
DISPLAY 0.489362 (-5875 2250);
PAINT SKYBLUE (-5875 2250);
FORCEPROP 1 LAST VALUE 22UF
J 0
(-5875 2350);
DISPLAY 0.489362 (-5875 2350);
PAINT SKYBLUE (-5875 2350);
FORCEPROP 1 LAST VOLTAGE 4V
J 0
(-5875 2300);
DISPLAY 0.489362 (-5875 2300);
PAINT SKYBLUE (-5875 2300);
FORCEPROP 1 LAST PACK_TYPE C0402
J 0
(-5875 2100);
DISPLAY 0.489362 (-5875 2100);
PAINT SKYBLUE (-5875 2100);
FORCEPROP 2 LAST CDS_LIB pure_quanta
J 0
(-5925 2300);
PAINT MONO (-5925 2300);
DISPLAY INVISIBLE (-5925 2300);
FORCEPROP 1 LAST PATH I61
J 0
(-5875 2450);
DISPLAY 0.978723 (-5875 2450);
PAINT WHITE (-5875 2450);
DISPLAY INVISIBLE (-5875 2450);
FORCEPROP 1 LAST PART_NUMBER CH622KMEB02
J 0
(-5875 2150);
DISPLAY 0.489362 (-5875 2150);
PAINT SKYBLUE (-5875 2150);
DISPLAY INVISIBLE (-5875 2150);
FORCEADD Q_CAP..1
(-5925 3000);
FORCEPROP 1 LAST LOCATION C2580
J 0
(-5875 3100);
DISPLAY 0.489362 (-5875 3100);
PAINT SKYBLUE (-5875 3100);
FORCEPROP 2 LAST $SEC 1
J 0
(-5875 3200);
DISPLAY 0.680851 (-5875 3200);
PAINT MONO (-5875 3200);
DISPLAY INVISIBLE (-5875 3200);
FORCEPROP 2 LAST CDS_SEC 1
J 0
(-5875 3200);
DISPLAY 1.021277 (-5875 3200);
DISPLAY INVISIBLE (-5875 3200);
FORCEPROP 1 LASTPIN (-5925 3100) $PN 1
J 0
(-5915 3080);
DISPLAY 0.489362 (-5915 3080);
FORCEPROP 1 LASTPIN (-5925 2900) $PN 2
J 0
(-5915 2880);
DISPLAY 0.489362 (-5915 2880);
FORCEPROP 1 LAST MATERIAL X6S
J 0
(-5875 2900);
DISPLAY 0.489362 (-5875 2900);
PAINT SKYBLUE (-5875 2900);
FORCEPROP 1 LAST TOLERANCE 20%
J 0
(-5875 2950);
DISPLAY 0.489362 (-5875 2950);
PAINT SKYBLUE (-5875 2950);
FORCEPROP 1 LAST VALUE 22UF
J 0
(-5875 3050);
DISPLAY 0.489362 (-5875 3050);
PAINT SKYBLUE (-5875 3050);
FORCEPROP 1 LAST VOLTAGE 4V
J 0
(-5875 3000);
DISPLAY 0.489362 (-5875 3000);
PAINT SKYBLUE (-5875 3000);
FORCEPROP 1 LAST PACK_TYPE C0402
J 0
(-5875 2800);
DISPLAY 0.489362 (-5875 2800);
PAINT SKYBLUE (-5875 2800);
FORCEPROP 2 LAST CDS_LIB pure_quanta
J 0
(-5925 3000);
PAINT MONO (-5925 3000);
DISPLAY INVISIBLE (-5925 3000);
FORCEPROP 1 LAST PATH I62
J 0
(-5875 3150);
DISPLAY 0.978723 (-5875 3150);
PAINT WHITE (-5875 3150);
DISPLAY INVISIBLE (-5875 3150);
FORCEPROP 1 LAST PART_NUMBER CH622KMEB02
J 0
(-5875 2850);
DISPLAY 0.489362 (-5875 2850);
PAINT SKYBLUE (-5875 2850);
DISPLAY INVISIBLE (-5875 2850);
FORCEADD Q_CAP..1
(-5475 2300);
FORCEPROP 1 LAST LOCATION C2588
J 0
(-5425 2400);
DISPLAY 0.489362 (-5425 2400);
PAINT SKYBLUE (-5425 2400);
FORCEPROP 2 LAST $SEC 1
J 0
(-5425 2500);
DISPLAY 0.680851 (-5425 2500);
PAINT MONO (-5425 2500);
DISPLAY INVISIBLE (-5425 2500);
FORCEPROP 2 LAST CDS_SEC 1
J 0
(-5425 2500);
DISPLAY 1.021277 (-5425 2500);
DISPLAY INVISIBLE (-5425 2500);
FORCEPROP 1 LASTPIN (-5475 2400) $PN 1
J 0
(-5465 2380);
DISPLAY 0.489362 (-5465 2380);
FORCEPROP 1 LASTPIN (-5475 2200) $PN 2
J 0
(-5465 2180);
DISPLAY 0.489362 (-5465 2180);
FORCEPROP 1 LAST MATERIAL X6S
J 0
(-5425 2200);
DISPLAY 0.489362 (-5425 2200);
PAINT SKYBLUE (-5425 2200);
FORCEPROP 1 LAST TOLERANCE 20%
J 0
(-5425 2250);
DISPLAY 0.489362 (-5425 2250);
PAINT SKYBLUE (-5425 2250);
FORCEPROP 1 LAST VALUE 22UF
J 0
(-5425 2350);
DISPLAY 0.489362 (-5425 2350);
PAINT SKYBLUE (-5425 2350);
FORCEPROP 1 LAST VOLTAGE 4V
J 0
(-5425 2300);
DISPLAY 0.489362 (-5425 2300);
PAINT SKYBLUE (-5425 2300);
FORCEPROP 1 LAST PACK_TYPE C0402
J 0
(-5425 2100);
DISPLAY 0.489362 (-5425 2100);
PAINT SKYBLUE (-5425 2100);
FORCEPROP 2 LAST CDS_LIB pure_quanta
J 0
(-5475 2300);
PAINT MONO (-5475 2300);
DISPLAY INVISIBLE (-5475 2300);
FORCEPROP 1 LAST PATH I63
J 0
(-5425 2450);
DISPLAY 0.978723 (-5425 2450);
PAINT WHITE (-5425 2450);
DISPLAY INVISIBLE (-5425 2450);
FORCEPROP 1 LAST PART_NUMBER CH622KMEB02
J 0
(-5425 2150);
DISPLAY 0.489362 (-5425 2150);
PAINT SKYBLUE (-5425 2150);
DISPLAY INVISIBLE (-5425 2150);
FORCEADD Q_CAP..1
(-5475 3000);
FORCEPROP 1 LAST LOCATION C2587
J 0
(-5425 3100);
DISPLAY 0.489362 (-5425 3100);
PAINT SKYBLUE (-5425 3100);
FORCEPROP 2 LAST $SEC 1
J 0
(-5425 3200);
DISPLAY 0.680851 (-5425 3200);
PAINT MONO (-5425 3200);
DISPLAY INVISIBLE (-5425 3200);
FORCEPROP 2 LAST CDS_SEC 1
J 0
(-5425 3200);
DISPLAY 1.021277 (-5425 3200);
DISPLAY INVISIBLE (-5425 3200);
FORCEPROP 1 LASTPIN (-5475 3100) $PN 1
J 0
(-5465 3080);
DISPLAY 0.489362 (-5465 3080);
FORCEPROP 1 LASTPIN (-5475 2900) $PN 2
J 0
(-5465 2880);
DISPLAY 0.489362 (-5465 2880);
FORCEPROP 1 LAST MATERIAL X6S
J 0
(-5425 2900);
DISPLAY 0.489362 (-5425 2900);
PAINT SKYBLUE (-5425 2900);
FORCEPROP 1 LAST TOLERANCE 20%
J 0
(-5425 2950);
DISPLAY 0.489362 (-5425 2950);
PAINT SKYBLUE (-5425 2950);
FORCEPROP 1 LAST VALUE 22UF
J 0
(-5425 3050);
DISPLAY 0.489362 (-5425 3050);
PAINT SKYBLUE (-5425 3050);
FORCEPROP 1 LAST VOLTAGE 4V
J 0
(-5425 3000);
DISPLAY 0.489362 (-5425 3000);
PAINT SKYBLUE (-5425 3000);
FORCEPROP 1 LAST PACK_TYPE C0402
J 0
(-5425 2800);
DISPLAY 0.489362 (-5425 2800);
PAINT SKYBLUE (-5425 2800);
FORCEPROP 2 LAST CDS_LIB pure_quanta
J 0
(-5475 3000);
PAINT MONO (-5475 3000);
DISPLAY INVISIBLE (-5475 3000);
FORCEPROP 1 LAST PATH I64
J 0
(-5425 3150);
DISPLAY 0.978723 (-5425 3150);
PAINT WHITE (-5425 3150);
DISPLAY INVISIBLE (-5425 3150);
FORCEPROP 1 LAST PART_NUMBER CH622KMEB02
J 0
(-5425 2850);
DISPLAY 0.489362 (-5425 2850);
PAINT SKYBLUE (-5425 2850);
DISPLAY INVISIBLE (-5425 2850);
FORCEADD Q_CAP..1
(-5925 3725);
FORCEPROP 1 LAST LOCATION C2579
J 0
(-5875 3825);
DISPLAY 0.489362 (-5875 3825);
PAINT SKYBLUE (-5875 3825);
FORCEPROP 2 LAST $SEC 1
J 0
(-5875 3925);
DISPLAY 0.680851 (-5875 3925);
PAINT MONO (-5875 3925);
DISPLAY INVISIBLE (-5875 3925);
FORCEPROP 2 LAST CDS_SEC 1
J 0
(-5875 3925);
DISPLAY 1.021277 (-5875 3925);
DISPLAY INVISIBLE (-5875 3925);
FORCEPROP 1 LASTPIN (-5925 3825) $PN 1
J 0
(-5915 3805);
DISPLAY 0.489362 (-5915 3805);
FORCEPROP 1 LASTPIN (-5925 3625) $PN 2
J 0
(-5915 3605);
DISPLAY 0.489362 (-5915 3605);
FORCEPROP 1 LAST MATERIAL X6S
J 0
(-5875 3625);
DISPLAY 0.489362 (-5875 3625);
PAINT SKYBLUE (-5875 3625);
FORCEPROP 1 LAST TOLERANCE 20%
J 0
(-5875 3675);
DISPLAY 0.489362 (-5875 3675);
PAINT SKYBLUE (-5875 3675);
FORCEPROP 1 LAST VALUE 22UF
J 0
(-5875 3775);
DISPLAY 0.489362 (-5875 3775);
PAINT SKYBLUE (-5875 3775);
FORCEPROP 1 LAST VOLTAGE 4V
J 0
(-5875 3725);
DISPLAY 0.489362 (-5875 3725);
PAINT SKYBLUE (-5875 3725);
FORCEPROP 1 LAST PACK_TYPE C0402
J 0
(-5875 3525);
DISPLAY 0.489362 (-5875 3525);
PAINT SKYBLUE (-5875 3525);
FORCEPROP 2 LAST CDS_LIB pure_quanta
J 0
(-5925 3725);
PAINT MONO (-5925 3725);
DISPLAY INVISIBLE (-5925 3725);
FORCEPROP 1 LAST PATH I65
J 0
(-5875 3875);
DISPLAY 0.978723 (-5875 3875);
PAINT WHITE (-5875 3875);
DISPLAY INVISIBLE (-5875 3875);
FORCEPROP 1 LAST PART_NUMBER CH622KMEB02
J 0
(-5875 3575);
DISPLAY 0.489362 (-5875 3575);
PAINT SKYBLUE (-5875 3575);
DISPLAY INVISIBLE (-5875 3575);
FORCEADD Q_CAP..1
(-5475 3725);
FORCEPROP 1 LAST LOCATION C2586
J 0
(-5425 3825);
DISPLAY 0.489362 (-5425 3825);
PAINT SKYBLUE (-5425 3825);
FORCEPROP 2 LAST $SEC 1
J 0
(-5425 3925);
DISPLAY 0.680851 (-5425 3925);
PAINT MONO (-5425 3925);
DISPLAY INVISIBLE (-5425 3925);
FORCEPROP 2 LAST CDS_SEC 1
J 0
(-5425 3925);
DISPLAY 1.021277 (-5425 3925);
DISPLAY INVISIBLE (-5425 3925);
FORCEPROP 1 LASTPIN (-5475 3825) $PN 1
J 0
(-5465 3805);
DISPLAY 0.489362 (-5465 3805);
FORCEPROP 1 LASTPIN (-5475 3625) $PN 2
J 0
(-5465 3605);
DISPLAY 0.489362 (-5465 3605);
FORCEPROP 1 LAST MATERIAL X6S
J 0
(-5425 3625);
DISPLAY 0.489362 (-5425 3625);
PAINT SKYBLUE (-5425 3625);
FORCEPROP 1 LAST TOLERANCE 20%
J 0
(-5425 3675);
DISPLAY 0.489362 (-5425 3675);
PAINT SKYBLUE (-5425 3675);
FORCEPROP 1 LAST VALUE 22UF
J 0
(-5425 3775);
DISPLAY 0.489362 (-5425 3775);
PAINT SKYBLUE (-5425 3775);
FORCEPROP 1 LAST VOLTAGE 4V
J 0
(-5425 3725);
DISPLAY 0.489362 (-5425 3725);
PAINT SKYBLUE (-5425 3725);
FORCEPROP 1 LAST PACK_TYPE C0402
J 0
(-5425 3525);
DISPLAY 0.489362 (-5425 3525);
PAINT SKYBLUE (-5425 3525);
FORCEPROP 2 LAST CDS_LIB pure_quanta
J 0
(-5475 3725);
PAINT MONO (-5475 3725);
DISPLAY INVISIBLE (-5475 3725);
FORCEPROP 1 LAST PATH I66
J 0
(-5425 3875);
DISPLAY 0.978723 (-5425 3875);
PAINT WHITE (-5425 3875);
DISPLAY INVISIBLE (-5425 3875);
FORCEPROP 1 LAST PART_NUMBER CH622KMEB02
J 0
(-5425 3575);
DISPLAY 0.489362 (-5425 3575);
PAINT SKYBLUE (-5425 3575);
DISPLAY INVISIBLE (-5425 3575);
FORCEADD Q_CAP..1
(-5075 2300);
FORCEPROP 1 LAST LOCATION C2595
J 0
(-5025 2400);
DISPLAY 0.489362 (-5025 2400);
PAINT SKYBLUE (-5025 2400);
FORCEPROP 2 LAST $SEC 1
J 0
(-5025 2500);
DISPLAY 0.680851 (-5025 2500);
PAINT MONO (-5025 2500);
DISPLAY INVISIBLE (-5025 2500);
FORCEPROP 2 LAST CDS_SEC 1
J 0
(-5025 2500);
DISPLAY 1.021277 (-5025 2500);
DISPLAY INVISIBLE (-5025 2500);
FORCEPROP 1 LASTPIN (-5075 2400) $PN 1
J 0
(-5065 2380);
DISPLAY 0.489362 (-5065 2380);
FORCEPROP 1 LASTPIN (-5075 2200) $PN 2
J 0
(-5065 2180);
DISPLAY 0.489362 (-5065 2180);
FORCEPROP 1 LAST MATERIAL X6S
J 0
(-5025 2200);
DISPLAY 0.489362 (-5025 2200);
PAINT SKYBLUE (-5025 2200);
FORCEPROP 1 LAST TOLERANCE 20%
J 0
(-5025 2250);
DISPLAY 0.489362 (-5025 2250);
PAINT SKYBLUE (-5025 2250);
FORCEPROP 1 LAST VALUE 22UF
J 0
(-5025 2350);
DISPLAY 0.489362 (-5025 2350);
PAINT SKYBLUE (-5025 2350);
FORCEPROP 1 LAST VOLTAGE 4V
J 0
(-5025 2300);
DISPLAY 0.489362 (-5025 2300);
PAINT SKYBLUE (-5025 2300);
FORCEPROP 1 LAST PACK_TYPE C0402
J 0
(-5025 2100);
DISPLAY 0.489362 (-5025 2100);
PAINT SKYBLUE (-5025 2100);
FORCEPROP 2 LAST CDS_LIB pure_quanta
J 0
(-5075 2300);
PAINT MONO (-5075 2300);
DISPLAY INVISIBLE (-5075 2300);
FORCEPROP 1 LAST PATH I67
J 0
(-5025 2450);
DISPLAY 0.978723 (-5025 2450);
PAINT WHITE (-5025 2450);
DISPLAY INVISIBLE (-5025 2450);
FORCEPROP 1 LAST PART_NUMBER CH622KMEB02
J 0
(-5025 2150);
DISPLAY 0.489362 (-5025 2150);
PAINT SKYBLUE (-5025 2150);
DISPLAY INVISIBLE (-5025 2150);
FORCEADD UNIVERSAL_GND..1
(-5075 2625);
FORCEPROP 3 LASTPIN (-5075 2675) SIG_NAME GND\g
J 0
(-5065 2685);
DISPLAY 0.659574 (-5065 2685);
PAINT MONO (-5065 2685);
DISPLAY INVISIBLE (-5065 2685);
FORCEPROP 2 LAST CDS_LIB pure_quanta_power
J 0
(-5075 2625);
PAINT MONO (-5075 2625);
DISPLAY INVISIBLE (-5075 2625);
FORCEPROP 1 LAST HDL_POWER GND
J 1
(-5050 2550);
DISPLAY 0.872340 (-5050 2550);
PAINT GREEN (-5050 2550);
DISPLAY INVISIBLE (-5050 2550);
FORCEPROP 1 LAST PATH I68
J 0
(-5000 2625);
DISPLAY 0.872340 (-5000 2625);
PAINT AQUA (-5000 2625);
DISPLAY INVISIBLE (-5000 2625);
FORCEADD Q_CAP..1
(-5075 3000);
FORCEPROP 1 LAST LOCATION C2594
J 0
(-5025 3100);
DISPLAY 0.489362 (-5025 3100);
PAINT SKYBLUE (-5025 3100);
FORCEPROP 2 LAST $SEC 1
J 0
(-5025 3200);
DISPLAY 0.680851 (-5025 3200);
PAINT MONO (-5025 3200);
DISPLAY INVISIBLE (-5025 3200);
FORCEPROP 2 LAST CDS_SEC 1
J 0
(-5025 3200);
DISPLAY 1.021277 (-5025 3200);
DISPLAY INVISIBLE (-5025 3200);
FORCEPROP 1 LASTPIN (-5075 3100) $PN 1
J 0
(-5065 3080);
DISPLAY 0.489362 (-5065 3080);
FORCEPROP 1 LASTPIN (-5075 2900) $PN 2
J 0
(-5065 2880);
DISPLAY 0.489362 (-5065 2880);
FORCEPROP 1 LAST MATERIAL X6S
J 0
(-5025 2900);
DISPLAY 0.489362 (-5025 2900);
PAINT SKYBLUE (-5025 2900);
FORCEPROP 1 LAST TOLERANCE 20%
J 0
(-5025 2950);
DISPLAY 0.489362 (-5025 2950);
PAINT SKYBLUE (-5025 2950);
FORCEPROP 1 LAST VALUE 22UF
J 0
(-5025 3050);
DISPLAY 0.489362 (-5025 3050);
PAINT SKYBLUE (-5025 3050);
FORCEPROP 1 LAST VOLTAGE 4V
J 0
(-5025 3000);
DISPLAY 0.489362 (-5025 3000);
PAINT SKYBLUE (-5025 3000);
FORCEPROP 1 LAST PACK_TYPE C0402
J 0
(-5025 2800);
DISPLAY 0.489362 (-5025 2800);
PAINT SKYBLUE (-5025 2800);
FORCEPROP 2 LAST CDS_LIB pure_quanta
J 0
(-5075 3000);
PAINT MONO (-5075 3000);
DISPLAY INVISIBLE (-5075 3000);
FORCEPROP 1 LAST PATH I69
J 0
(-5025 3150);
DISPLAY 0.978723 (-5025 3150);
PAINT WHITE (-5025 3150);
DISPLAY INVISIBLE (-5025 3150);
FORCEPROP 1 LAST PART_NUMBER CH622KMEB02
J 0
(-5025 2850);
DISPLAY 0.489362 (-5025 2850);
PAINT SKYBLUE (-5025 2850);
DISPLAY INVISIBLE (-5025 2850);
FORCEADD Q_CAP..1
(-9075 2300);
FORCEPROP 1 LAST LOCATION C2532
J 0
(-9025 2400);
DISPLAY 0.489362 (-9025 2400);
PAINT SKYBLUE (-9025 2400);
FORCEPROP 2 LAST $SEC 1
J 0
(-9025 2500);
DISPLAY 0.680851 (-9025 2500);
PAINT MONO (-9025 2500);
DISPLAY INVISIBLE (-9025 2500);
FORCEPROP 2 LAST CDS_SEC 1
J 0
(-9025 2500);
DISPLAY 1.021277 (-9025 2500);
DISPLAY INVISIBLE (-9025 2500);
FORCEPROP 1 LASTPIN (-9075 2400) $PN 1
J 0
(-9065 2380);
DISPLAY 0.489362 (-9065 2380);
FORCEPROP 1 LASTPIN (-9075 2200) $PN 2
J 0
(-9065 2180);
DISPLAY 0.489362 (-9065 2180);
FORCEPROP 1 LAST MATERIAL X6S
J 0
(-9025 2200);
DISPLAY 0.489362 (-9025 2200);
PAINT SKYBLUE (-9025 2200);
FORCEPROP 1 LAST TOLERANCE 20%
J 0
(-9025 2250);
DISPLAY 0.489362 (-9025 2250);
PAINT SKYBLUE (-9025 2250);
FORCEPROP 1 LAST VALUE 22UF
J 0
(-9025 2350);
DISPLAY 0.489362 (-9025 2350);
PAINT SKYBLUE (-9025 2350);
FORCEPROP 1 LAST VOLTAGE 4V
J 0
(-9025 2300);
DISPLAY 0.489362 (-9025 2300);
PAINT SKYBLUE (-9025 2300);
FORCEPROP 1 LAST PACK_TYPE C0402
J 0
(-9025 2100);
DISPLAY 0.489362 (-9025 2100);
PAINT SKYBLUE (-9025 2100);
FORCEPROP 2 LAST CDS_LIB pure_quanta
J 0
(-9075 2300);
PAINT MONO (-9075 2300);
DISPLAY INVISIBLE (-9075 2300);
FORCEPROP 1 LAST PATH I7
J 0
(-9025 2450);
DISPLAY 0.978723 (-9025 2450);
PAINT WHITE (-9025 2450);
DISPLAY INVISIBLE (-9025 2450);
FORCEPROP 1 LAST PART_NUMBER CH622KMEB02
J 0
(-9025 2150);
DISPLAY 0.489362 (-9025 2150);
PAINT SKYBLUE (-9025 2150);
DISPLAY INVISIBLE (-9025 2150);
FORCEADD UNIVERSAL_POWER..1
(-4500 2275);
FORCEPROP 3 LASTPIN (-4500 2225) SIG_NAME PVDD11_S3_P0\g
J 0
(-4490 2235);
DISPLAY 0.659574 (-4490 2235);
PAINT MONO (-4490 2235);
DISPLAY INVISIBLE (-4490 2235);
FORCEPROP 1 LAST HDL_POWER PVDD11_S3_P0
J 1
(-4500 2325);
DISPLAY 0.489362 (-4500 2325);
PAINT GREEN (-4500 2325);
FORCEPROP 2 LAST CDS_LIB pure_quanta_power
J 0
(-4500 2275);
DISPLAY INVISIBLE (-4500 2275);
FORCEPROP 1 LAST PATH I70
J 0
(-4450 2300);
DISPLAY 0.872340 (-4450 2300);
PAINT AQUA (-4450 2300);
DISPLAY INVISIBLE (-4450 2300);
FORCEADD Q_CAP..1
(-4500 2625);
FORCEPROP 1 LAST LOCATION C2601
J 0
(-4450 2725);
DISPLAY 0.489362 (-4450 2725);
PAINT SKYBLUE (-4450 2725);
FORCEPROP 2 LAST $SEC 1
J 0
(-4450 2825);
DISPLAY 0.680851 (-4450 2825);
PAINT MONO (-4450 2825);
DISPLAY INVISIBLE (-4450 2825);
FORCEPROP 2 LAST CDS_SEC 1
J 0
(-4450 2825);
DISPLAY 1.021277 (-4450 2825);
DISPLAY INVISIBLE (-4450 2825);
FORCEPROP 1 LASTPIN (-4500 2725) $PN 1
J 0
(-4490 2705);
DISPLAY 0.489362 (-4490 2705);
FORCEPROP 1 LASTPIN (-4500 2525) $PN 2
J 0
(-4490 2505);
DISPLAY 0.489362 (-4490 2505);
FORCEPROP 1 LAST MATERIAL X6S
J 0
(-4450 2525);
DISPLAY 0.489362 (-4450 2525);
PAINT SKYBLUE (-4450 2525);
FORCEPROP 1 LAST TOLERANCE 20%
J 0
(-4450 2575);
DISPLAY 0.489362 (-4450 2575);
PAINT SKYBLUE (-4450 2575);
FORCEPROP 1 LAST VALUE 22UF
J 0
(-4450 2675);
DISPLAY 0.489362 (-4450 2675);
PAINT SKYBLUE (-4450 2675);
FORCEPROP 1 LAST VOLTAGE 4V
J 0
(-4450 2625);
DISPLAY 0.489362 (-4450 2625);
PAINT SKYBLUE (-4450 2625);
FORCEPROP 1 LAST PACK_TYPE C0402
J 0
(-4450 2425);
DISPLAY 0.489362 (-4450 2425);
PAINT SKYBLUE (-4450 2425);
FORCEPROP 2 LAST CDS_LIB pure_quanta
J 0
(-4500 2625);
PAINT MONO (-4500 2625);
DISPLAY INVISIBLE (-4500 2625);
FORCEPROP 1 LAST PATH I71
J 0
(-4450 2775);
DISPLAY 0.978723 (-4450 2775);
PAINT WHITE (-4450 2775);
DISPLAY INVISIBLE (-4450 2775);
FORCEPROP 1 LAST PART_NUMBER CH622KMEB02
J 0
(-4450 2475);
DISPLAY 0.489362 (-4450 2475);
PAINT SKYBLUE (-4450 2475);
DISPLAY INVISIBLE (-4450 2475);
FORCEADD UNIVERSAL_POWER..1
(-4500 2900);
FORCEPROP 3 LASTPIN (-4500 2850) SIG_NAME PVDD11_S3_P0\g
J 0
(-4490 2860);
DISPLAY 0.659574 (-4490 2860);
PAINT MONO (-4490 2860);
DISPLAY INVISIBLE (-4490 2860);
FORCEPROP 1 LAST HDL_POWER PVDD11_S3_P0
J 1
(-4500 2950);
DISPLAY 0.489362 (-4500 2950);
PAINT GREEN (-4500 2950);
FORCEPROP 2 LAST CDS_LIB pure_quanta_power
J 0
(-4500 2900);
DISPLAY INVISIBLE (-4500 2900);
FORCEPROP 1 LAST PATH I72
J 0
(-4450 2925);
DISPLAY 0.872340 (-4450 2925);
PAINT AQUA (-4450 2925);
DISPLAY INVISIBLE (-4450 2925);
FORCEADD UNIVERSAL_GND..1
(-5075 3350);
FORCEPROP 3 LASTPIN (-5075 3400) SIG_NAME GND\g
J 0
(-5065 3410);
DISPLAY 0.659574 (-5065 3410);
PAINT MONO (-5065 3410);
DISPLAY INVISIBLE (-5065 3410);
FORCEPROP 2 LAST CDS_LIB pure_quanta_power
J 0
(-5075 3350);
PAINT MONO (-5075 3350);
DISPLAY INVISIBLE (-5075 3350);
FORCEPROP 1 LAST HDL_POWER GND
J 1
(-5050 3275);
DISPLAY 0.872340 (-5050 3275);
PAINT GREEN (-5050 3275);
DISPLAY INVISIBLE (-5050 3275);
FORCEPROP 1 LAST PATH I73
J 0
(-5000 3350);
DISPLAY 0.872340 (-5000 3350);
PAINT AQUA (-5000 3350);
DISPLAY INVISIBLE (-5000 3350);
FORCEADD Q_CAP..1
(-5075 3725);
FORCEPROP 1 LAST LOCATION C2593
J 0
(-5025 3825);
DISPLAY 0.489362 (-5025 3825);
PAINT SKYBLUE (-5025 3825);
FORCEPROP 2 LAST $SEC 1
J 0
(-5025 3925);
DISPLAY 0.680851 (-5025 3925);
PAINT MONO (-5025 3925);
DISPLAY INVISIBLE (-5025 3925);
FORCEPROP 2 LAST CDS_SEC 1
J 0
(-5025 3925);
DISPLAY 1.021277 (-5025 3925);
DISPLAY INVISIBLE (-5025 3925);
FORCEPROP 1 LASTPIN (-5075 3825) $PN 1
J 0
(-5065 3805);
DISPLAY 0.489362 (-5065 3805);
FORCEPROP 1 LASTPIN (-5075 3625) $PN 2
J 0
(-5065 3605);
DISPLAY 0.489362 (-5065 3605);
FORCEPROP 1 LAST MATERIAL X6S
J 0
(-5025 3625);
DISPLAY 0.489362 (-5025 3625);
PAINT SKYBLUE (-5025 3625);
FORCEPROP 1 LAST TOLERANCE 20%
J 0
(-5025 3675);
DISPLAY 0.489362 (-5025 3675);
PAINT SKYBLUE (-5025 3675);
FORCEPROP 1 LAST VALUE 22UF
J 0
(-5025 3775);
DISPLAY 0.489362 (-5025 3775);
PAINT SKYBLUE (-5025 3775);
FORCEPROP 1 LAST VOLTAGE 4V
J 0
(-5025 3725);
DISPLAY 0.489362 (-5025 3725);
PAINT SKYBLUE (-5025 3725);
FORCEPROP 1 LAST PACK_TYPE C0402
J 0
(-5025 3525);
DISPLAY 0.489362 (-5025 3525);
PAINT SKYBLUE (-5025 3525);
FORCEPROP 2 LAST CDS_LIB pure_quanta
J 0
(-5075 3725);
PAINT MONO (-5075 3725);
DISPLAY INVISIBLE (-5075 3725);
FORCEPROP 1 LAST PATH I74
J 0
(-5025 3875);
DISPLAY 0.978723 (-5025 3875);
PAINT WHITE (-5025 3875);
DISPLAY INVISIBLE (-5025 3875);
FORCEPROP 1 LAST PART_NUMBER CH622KMEB02
J 0
(-5025 3575);
DISPLAY 0.489362 (-5025 3575);
PAINT SKYBLUE (-5025 3575);
DISPLAY INVISIBLE (-5025 3575);
FORCEADD UNIVERSAL_GND..1
(-5100 4050);
FORCEPROP 3 LASTPIN (-5100 4100) SIG_NAME GND\g
J 0
(-5090 4110);
DISPLAY 0.659574 (-5090 4110);
PAINT MONO (-5090 4110);
DISPLAY INVISIBLE (-5090 4110);
FORCEPROP 2 LAST CDS_LIB pure_quanta_power
J 0
(-5100 4050);
PAINT MONO (-5100 4050);
DISPLAY INVISIBLE (-5100 4050);
FORCEPROP 1 LAST HDL_POWER GND
J 1
(-5075 3975);
DISPLAY 0.872340 (-5075 3975);
PAINT GREEN (-5075 3975);
DISPLAY INVISIBLE (-5075 3975);
FORCEPROP 1 LAST PATH I75
J 0
(-5025 4050);
DISPLAY 0.872340 (-5025 4050);
PAINT AQUA (-5025 4050);
DISPLAY INVISIBLE (-5025 4050);
FORCEADD Q_CAP..1
(-4500 3275);
FORCEPROP 1 LAST LOCATION C2600
J 0
(-4450 3375);
DISPLAY 0.489362 (-4450 3375);
PAINT SKYBLUE (-4450 3375);
FORCEPROP 2 LAST $SEC 1
J 0
(-4450 3475);
DISPLAY 0.680851 (-4450 3475);
PAINT MONO (-4450 3475);
DISPLAY INVISIBLE (-4450 3475);
FORCEPROP 2 LAST CDS_SEC 1
J 0
(-4450 3475);
DISPLAY 1.021277 (-4450 3475);
DISPLAY INVISIBLE (-4450 3475);
FORCEPROP 1 LASTPIN (-4500 3375) $PN 1
J 0
(-4490 3355);
DISPLAY 0.489362 (-4490 3355);
FORCEPROP 1 LASTPIN (-4500 3175) $PN 2
J 0
(-4490 3155);
DISPLAY 0.489362 (-4490 3155);
FORCEPROP 1 LAST MATERIAL X6S
J 0
(-4450 3175);
DISPLAY 0.489362 (-4450 3175);
PAINT SKYBLUE (-4450 3175);
FORCEPROP 1 LAST TOLERANCE 20%
J 0
(-4450 3225);
DISPLAY 0.489362 (-4450 3225);
PAINT SKYBLUE (-4450 3225);
FORCEPROP 1 LAST VALUE 22UF
J 0
(-4450 3325);
DISPLAY 0.489362 (-4450 3325);
PAINT SKYBLUE (-4450 3325);
FORCEPROP 1 LAST VOLTAGE 4V
J 0
(-4450 3275);
DISPLAY 0.489362 (-4450 3275);
PAINT SKYBLUE (-4450 3275);
FORCEPROP 1 LAST PACK_TYPE C0402
J 0
(-4450 3075);
DISPLAY 0.489362 (-4450 3075);
PAINT SKYBLUE (-4450 3075);
FORCEPROP 2 LAST CDS_LIB pure_quanta
J 0
(-4500 3275);
PAINT MONO (-4500 3275);
DISPLAY INVISIBLE (-4500 3275);
FORCEPROP 1 LAST PATH I76
J 0
(-4450 3425);
DISPLAY 0.978723 (-4450 3425);
PAINT WHITE (-4450 3425);
DISPLAY INVISIBLE (-4450 3425);
FORCEPROP 1 LAST PART_NUMBER CH622KMEB02
J 0
(-4450 3125);
DISPLAY 0.489362 (-4450 3125);
PAINT SKYBLUE (-4450 3125);
DISPLAY INVISIBLE (-4450 3125);
FORCEADD UNIVERSAL_POWER..1
(-4500 3550);
FORCEPROP 3 LASTPIN (-4500 3500) SIG_NAME PVDD11_S3_P0\g
J 0
(-4490 3510);
DISPLAY 0.659574 (-4490 3510);
PAINT MONO (-4490 3510);
DISPLAY INVISIBLE (-4490 3510);
FORCEPROP 1 LAST HDL_POWER PVDD11_S3_P0
J 1
(-4500 3600);
DISPLAY 0.489362 (-4500 3600);
PAINT GREEN (-4500 3600);
FORCEPROP 2 LAST CDS_LIB pure_quanta_power
J 0
(-4500 3550);
DISPLAY INVISIBLE (-4500 3550);
FORCEPROP 1 LAST PATH I77
J 0
(-4450 3575);
DISPLAY 0.872340 (-4450 3575);
PAINT AQUA (-4450 3575);
DISPLAY INVISIBLE (-4450 3575);
FORCEADD Q_CAP..1
(-8200 4425);
FORCEPROP 1 LAST LOCATION C2543
J 0
(-8150 4525);
DISPLAY 0.489362 (-8150 4525);
PAINT SKYBLUE (-8150 4525);
FORCEPROP 2 LAST $SEC 1
J 0
(-8150 4625);
DISPLAY 0.680851 (-8150 4625);
PAINT MONO (-8150 4625);
DISPLAY INVISIBLE (-8150 4625);
FORCEPROP 2 LAST CDS_SEC 1
J 0
(-8150 4625);
DISPLAY 1.021277 (-8150 4625);
DISPLAY INVISIBLE (-8150 4625);
FORCEPROP 1 LASTPIN (-8200 4525) $PN 1
J 0
(-8190 4505);
DISPLAY 0.489362 (-8190 4505);
FORCEPROP 1 LASTPIN (-8200 4325) $PN 2
J 0
(-8190 4305);
DISPLAY 0.489362 (-8190 4305);
FORCEPROP 1 LAST MATERIAL X6S
J 0
(-8150 4325);
DISPLAY 0.489362 (-8150 4325);
PAINT SKYBLUE (-8150 4325);
FORCEPROP 1 LAST TOLERANCE 20%
J 0
(-8150 4375);
DISPLAY 0.489362 (-8150 4375);
PAINT SKYBLUE (-8150 4375);
FORCEPROP 1 LAST VALUE 22UF
J 0
(-8150 4475);
DISPLAY 0.489362 (-8150 4475);
PAINT SKYBLUE (-8150 4475);
FORCEPROP 1 LAST VOLTAGE 4V
J 0
(-8150 4425);
DISPLAY 0.489362 (-8150 4425);
PAINT SKYBLUE (-8150 4425);
FORCEPROP 1 LAST PACK_TYPE C0402
J 0
(-8150 4225);
DISPLAY 0.489362 (-8150 4225);
PAINT SKYBLUE (-8150 4225);
FORCEPROP 2 LAST CDS_LIB pure_quanta
J 0
(-8200 4425);
PAINT MONO (-8200 4425);
DISPLAY INVISIBLE (-8200 4425);
FORCEPROP 1 LAST PATH I78
J 0
(-8150 4575);
DISPLAY 0.978723 (-8150 4575);
PAINT WHITE (-8150 4575);
DISPLAY INVISIBLE (-8150 4575);
FORCEPROP 1 LAST PART_NUMBER CH622KMEB02
J 0
(-8150 4275);
DISPLAY 0.489362 (-8150 4275);
PAINT SKYBLUE (-8150 4275);
DISPLAY INVISIBLE (-8150 4275);
FORCEADD Q_CAP..1
(-8200 5150);
FORCEPROP 1 LAST LOCATION C2542
J 0
(-8150 5250);
DISPLAY 0.489362 (-8150 5250);
PAINT SKYBLUE (-8150 5250);
FORCEPROP 2 LAST $SEC 1
J 0
(-8150 5350);
DISPLAY 0.680851 (-8150 5350);
PAINT MONO (-8150 5350);
DISPLAY INVISIBLE (-8150 5350);
FORCEPROP 2 LAST CDS_SEC 1
J 0
(-8150 5350);
DISPLAY 1.021277 (-8150 5350);
DISPLAY INVISIBLE (-8150 5350);
FORCEPROP 1 LASTPIN (-8200 5250) $PN 1
J 0
(-8190 5230);
DISPLAY 0.489362 (-8190 5230);
FORCEPROP 1 LASTPIN (-8200 5050) $PN 2
J 0
(-8190 5030);
DISPLAY 0.489362 (-8190 5030);
FORCEPROP 1 LAST MATERIAL X6S
J 0
(-8150 5050);
DISPLAY 0.489362 (-8150 5050);
PAINT SKYBLUE (-8150 5050);
FORCEPROP 1 LAST TOLERANCE 20%
J 0
(-8150 5100);
DISPLAY 0.489362 (-8150 5100);
PAINT SKYBLUE (-8150 5100);
FORCEPROP 1 LAST VALUE 22UF
J 0
(-8150 5200);
DISPLAY 0.489362 (-8150 5200);
PAINT SKYBLUE (-8150 5200);
FORCEPROP 1 LAST VOLTAGE 4V
J 0
(-8150 5150);
DISPLAY 0.489362 (-8150 5150);
PAINT SKYBLUE (-8150 5150);
FORCEPROP 1 LAST PACK_TYPE C0402
J 0
(-8150 4950);
DISPLAY 0.489362 (-8150 4950);
PAINT SKYBLUE (-8150 4950);
FORCEPROP 2 LAST CDS_LIB pure_quanta
J 0
(-8200 5150);
PAINT MONO (-8200 5150);
DISPLAY INVISIBLE (-8200 5150);
FORCEPROP 1 LAST PATH I79
J 0
(-8150 5300);
DISPLAY 0.978723 (-8150 5300);
PAINT WHITE (-8150 5300);
DISPLAY INVISIBLE (-8150 5300);
FORCEPROP 1 LAST PART_NUMBER CH622KMEB02
J 0
(-8150 5000);
DISPLAY 0.489362 (-8150 5000);
PAINT SKYBLUE (-8150 5000);
DISPLAY INVISIBLE (-8150 5000);
FORCEADD UNIVERSAL_POWER..1
(-9075 2575);
FORCEPROP 3 LASTPIN (-9075 2525) SIG_NAME PVDDCR_SOC_P0\g
J 0
(-9065 2535);
DISPLAY 0.659574 (-9065 2535);
PAINT MONO (-9065 2535);
DISPLAY INVISIBLE (-9065 2535);
FORCEPROP 1 LAST HDL_POWER PVDDCR_SOC_P0
J 1
(-9075 2625);
DISPLAY 0.489362 (-9075 2625);
PAINT GREEN (-9075 2625);
FORCEPROP 2 LAST CDS_LIB pure_quanta_power
J 0
(-9075 2575);
DISPLAY INVISIBLE (-9075 2575);
FORCEPROP 1 LAST PATH I8
J 0
(-9025 2600);
DISPLAY 0.872340 (-9025 2600);
PAINT AQUA (-9025 2600);
DISPLAY INVISIBLE (-9025 2600);
FORCEADD Q_CAP..1
(-7750 4425);
FORCEPROP 1 LAST LOCATION C2550
J 0
(-7700 4525);
DISPLAY 0.489362 (-7700 4525);
PAINT SKYBLUE (-7700 4525);
FORCEPROP 2 LAST $SEC 1
J 0
(-7700 4625);
DISPLAY 0.680851 (-7700 4625);
PAINT MONO (-7700 4625);
DISPLAY INVISIBLE (-7700 4625);
FORCEPROP 2 LAST CDS_SEC 1
J 0
(-7700 4625);
DISPLAY 1.021277 (-7700 4625);
DISPLAY INVISIBLE (-7700 4625);
FORCEPROP 1 LASTPIN (-7750 4525) $PN 1
J 0
(-7740 4505);
DISPLAY 0.489362 (-7740 4505);
FORCEPROP 1 LASTPIN (-7750 4325) $PN 2
J 0
(-7740 4305);
DISPLAY 0.489362 (-7740 4305);
FORCEPROP 1 LAST MATERIAL X6S
J 0
(-7700 4325);
DISPLAY 0.489362 (-7700 4325);
PAINT SKYBLUE (-7700 4325);
FORCEPROP 1 LAST TOLERANCE 20%
J 0
(-7700 4375);
DISPLAY 0.489362 (-7700 4375);
PAINT SKYBLUE (-7700 4375);
FORCEPROP 1 LAST VALUE 22UF
J 0
(-7700 4475);
DISPLAY 0.489362 (-7700 4475);
PAINT SKYBLUE (-7700 4475);
FORCEPROP 1 LAST VOLTAGE 4V
J 0
(-7700 4425);
DISPLAY 0.489362 (-7700 4425);
PAINT SKYBLUE (-7700 4425);
FORCEPROP 1 LAST PACK_TYPE C0402
J 0
(-7700 4225);
DISPLAY 0.489362 (-7700 4225);
PAINT SKYBLUE (-7700 4225);
FORCEPROP 2 LAST CDS_LIB pure_quanta
J 0
(-7750 4425);
PAINT MONO (-7750 4425);
DISPLAY INVISIBLE (-7750 4425);
FORCEPROP 1 LAST PATH I80
J 0
(-7700 4575);
DISPLAY 0.978723 (-7700 4575);
PAINT WHITE (-7700 4575);
DISPLAY INVISIBLE (-7700 4575);
FORCEPROP 1 LAST PART_NUMBER CH622KMEB02
J 0
(-7700 4275);
DISPLAY 0.489362 (-7700 4275);
PAINT SKYBLUE (-7700 4275);
DISPLAY INVISIBLE (-7700 4275);
FORCEADD Q_CAP..1
(-7750 5150);
FORCEPROP 1 LAST LOCATION C2549
J 0
(-7700 5250);
DISPLAY 0.489362 (-7700 5250);
PAINT SKYBLUE (-7700 5250);
FORCEPROP 2 LAST $SEC 1
J 0
(-7700 5350);
DISPLAY 0.680851 (-7700 5350);
PAINT MONO (-7700 5350);
DISPLAY INVISIBLE (-7700 5350);
FORCEPROP 2 LAST CDS_SEC 1
J 0
(-7700 5350);
DISPLAY 1.021277 (-7700 5350);
DISPLAY INVISIBLE (-7700 5350);
FORCEPROP 1 LASTPIN (-7750 5250) $PN 1
J 0
(-7740 5230);
DISPLAY 0.489362 (-7740 5230);
FORCEPROP 1 LASTPIN (-7750 5050) $PN 2
J 0
(-7740 5030);
DISPLAY 0.489362 (-7740 5030);
FORCEPROP 1 LAST MATERIAL X6S
J 0
(-7700 5050);
DISPLAY 0.489362 (-7700 5050);
PAINT SKYBLUE (-7700 5050);
FORCEPROP 1 LAST TOLERANCE 20%
J 0
(-7700 5100);
DISPLAY 0.489362 (-7700 5100);
PAINT SKYBLUE (-7700 5100);
FORCEPROP 1 LAST VALUE 22UF
J 0
(-7700 5200);
DISPLAY 0.489362 (-7700 5200);
PAINT SKYBLUE (-7700 5200);
FORCEPROP 1 LAST VOLTAGE 4V
J 0
(-7700 5150);
DISPLAY 0.489362 (-7700 5150);
PAINT SKYBLUE (-7700 5150);
FORCEPROP 1 LAST PACK_TYPE C0402
J 0
(-7700 4950);
DISPLAY 0.489362 (-7700 4950);
PAINT SKYBLUE (-7700 4950);
FORCEPROP 2 LAST CDS_LIB pure_quanta
J 0
(-7750 5150);
PAINT MONO (-7750 5150);
DISPLAY INVISIBLE (-7750 5150);
FORCEPROP 1 LAST PATH I81
J 0
(-7700 5300);
DISPLAY 0.978723 (-7700 5300);
PAINT WHITE (-7700 5300);
DISPLAY INVISIBLE (-7700 5300);
FORCEPROP 1 LAST PART_NUMBER CH622KMEB02
J 0
(-7700 5000);
DISPLAY 0.489362 (-7700 5000);
PAINT SKYBLUE (-7700 5000);
DISPLAY INVISIBLE (-7700 5000);
FORCEADD Q_CAP..1
(-7300 4425);
FORCEPROP 1 LAST LOCATION C2557
J 0
(-7250 4525);
DISPLAY 0.489362 (-7250 4525);
PAINT SKYBLUE (-7250 4525);
FORCEPROP 2 LAST $SEC 1
J 0
(-7250 4625);
DISPLAY 0.680851 (-7250 4625);
PAINT MONO (-7250 4625);
DISPLAY INVISIBLE (-7250 4625);
FORCEPROP 2 LAST CDS_SEC 1
J 0
(-7250 4625);
DISPLAY 1.021277 (-7250 4625);
DISPLAY INVISIBLE (-7250 4625);
FORCEPROP 1 LASTPIN (-7300 4525) $PN 1
J 0
(-7290 4505);
DISPLAY 0.489362 (-7290 4505);
FORCEPROP 1 LASTPIN (-7300 4325) $PN 2
J 0
(-7290 4305);
DISPLAY 0.489362 (-7290 4305);
FORCEPROP 1 LAST MATERIAL X6S
J 0
(-7250 4325);
DISPLAY 0.489362 (-7250 4325);
PAINT SKYBLUE (-7250 4325);
FORCEPROP 1 LAST TOLERANCE 20%
J 0
(-7250 4375);
DISPLAY 0.489362 (-7250 4375);
PAINT SKYBLUE (-7250 4375);
FORCEPROP 1 LAST VALUE 22UF
J 0
(-7250 4475);
DISPLAY 0.489362 (-7250 4475);
PAINT SKYBLUE (-7250 4475);
FORCEPROP 1 LAST VOLTAGE 4V
J 0
(-7250 4425);
DISPLAY 0.489362 (-7250 4425);
PAINT SKYBLUE (-7250 4425);
FORCEPROP 1 LAST PACK_TYPE C0402
J 0
(-7250 4225);
DISPLAY 0.489362 (-7250 4225);
PAINT SKYBLUE (-7250 4225);
FORCEPROP 2 LAST CDS_LIB pure_quanta
J 0
(-7300 4425);
PAINT MONO (-7300 4425);
DISPLAY INVISIBLE (-7300 4425);
FORCEPROP 1 LAST PATH I82
J 0
(-7250 4575);
DISPLAY 0.978723 (-7250 4575);
PAINT WHITE (-7250 4575);
DISPLAY INVISIBLE (-7250 4575);
FORCEPROP 1 LAST PART_NUMBER CH622KMEB02
J 0
(-7250 4275);
DISPLAY 0.489362 (-7250 4275);
PAINT SKYBLUE (-7250 4275);
DISPLAY INVISIBLE (-7250 4275);
FORCEADD Q_CAP..1
(-7300 5150);
FORCEPROP 1 LAST LOCATION C2556
J 0
(-7250 5250);
DISPLAY 0.489362 (-7250 5250);
PAINT SKYBLUE (-7250 5250);
FORCEPROP 2 LAST $SEC 1
J 0
(-7250 5350);
DISPLAY 0.680851 (-7250 5350);
PAINT MONO (-7250 5350);
DISPLAY INVISIBLE (-7250 5350);
FORCEPROP 2 LAST CDS_SEC 1
J 0
(-7250 5350);
DISPLAY 1.021277 (-7250 5350);
DISPLAY INVISIBLE (-7250 5350);
FORCEPROP 1 LASTPIN (-7300 5250) $PN 1
J 0
(-7290 5230);
DISPLAY 0.489362 (-7290 5230);
FORCEPROP 1 LASTPIN (-7300 5050) $PN 2
J 0
(-7290 5030);
DISPLAY 0.489362 (-7290 5030);
FORCEPROP 1 LAST MATERIAL X6S
J 0
(-7250 5050);
DISPLAY 0.489362 (-7250 5050);
PAINT SKYBLUE (-7250 5050);
FORCEPROP 1 LAST TOLERANCE 20%
J 0
(-7250 5100);
DISPLAY 0.489362 (-7250 5100);
PAINT SKYBLUE (-7250 5100);
FORCEPROP 1 LAST VALUE 22UF
J 0
(-7250 5200);
DISPLAY 0.489362 (-7250 5200);
PAINT SKYBLUE (-7250 5200);
FORCEPROP 1 LAST VOLTAGE 4V
J 0
(-7250 5150);
DISPLAY 0.489362 (-7250 5150);
PAINT SKYBLUE (-7250 5150);
FORCEPROP 1 LAST PACK_TYPE C0402
J 0
(-7250 4950);
DISPLAY 0.489362 (-7250 4950);
PAINT SKYBLUE (-7250 4950);
FORCEPROP 2 LAST CDS_LIB pure_quanta
J 0
(-7300 5150);
PAINT MONO (-7300 5150);
DISPLAY INVISIBLE (-7300 5150);
FORCEPROP 1 LAST PATH I83
J 0
(-7250 5300);
DISPLAY 0.978723 (-7250 5300);
PAINT WHITE (-7250 5300);
DISPLAY INVISIBLE (-7250 5300);
FORCEPROP 1 LAST PART_NUMBER CH622KMEB02
J 0
(-7250 5000);
DISPLAY 0.489362 (-7250 5000);
PAINT SKYBLUE (-7250 5000);
DISPLAY INVISIBLE (-7250 5000);
FORCEADD Q_CAP..1
(-8200 5900);
FORCEPROP 1 LAST LOCATION C2541
J 0
(-8150 6000);
DISPLAY 0.489362 (-8150 6000);
PAINT SKYBLUE (-8150 6000);
FORCEPROP 2 LAST $SEC 1
J 0
(-8150 6100);
DISPLAY 0.680851 (-8150 6100);
PAINT MONO (-8150 6100);
DISPLAY INVISIBLE (-8150 6100);
FORCEPROP 2 LAST CDS_SEC 1
J 0
(-8150 6100);
DISPLAY 1.021277 (-8150 6100);
DISPLAY INVISIBLE (-8150 6100);
FORCEPROP 1 LASTPIN (-8200 6000) $PN 1
J 0
(-8190 5980);
DISPLAY 0.489362 (-8190 5980);
FORCEPROP 1 LASTPIN (-8200 5800) $PN 2
J 0
(-8190 5780);
DISPLAY 0.489362 (-8190 5780);
FORCEPROP 1 LAST MATERIAL X6S
J 0
(-8150 5800);
DISPLAY 0.489362 (-8150 5800);
PAINT SKYBLUE (-8150 5800);
FORCEPROP 1 LAST TOLERANCE 20%
J 0
(-8150 5850);
DISPLAY 0.489362 (-8150 5850);
PAINT SKYBLUE (-8150 5850);
FORCEPROP 1 LAST VALUE 22UF
J 0
(-8150 5950);
DISPLAY 0.489362 (-8150 5950);
PAINT SKYBLUE (-8150 5950);
FORCEPROP 1 LAST VOLTAGE 4V
J 0
(-8150 5900);
DISPLAY 0.489362 (-8150 5900);
PAINT SKYBLUE (-8150 5900);
FORCEPROP 1 LAST PACK_TYPE C0402
J 0
(-8150 5700);
DISPLAY 0.489362 (-8150 5700);
PAINT SKYBLUE (-8150 5700);
FORCEPROP 2 LAST CDS_LIB pure_quanta
J 0
(-8200 5900);
PAINT MONO (-8200 5900);
DISPLAY INVISIBLE (-8200 5900);
FORCEPROP 1 LAST PATH I84
J 0
(-8150 6050);
DISPLAY 0.978723 (-8150 6050);
PAINT WHITE (-8150 6050);
DISPLAY INVISIBLE (-8150 6050);
FORCEPROP 1 LAST PART_NUMBER CH622KMEB02
J 0
(-8150 5750);
DISPLAY 0.489362 (-8150 5750);
PAINT SKYBLUE (-8150 5750);
DISPLAY INVISIBLE (-8150 5750);
FORCEADD Q_CAP..1
(-7750 5900);
FORCEPROP 1 LAST LOCATION C2548
J 0
(-7700 6000);
DISPLAY 0.489362 (-7700 6000);
PAINT SKYBLUE (-7700 6000);
FORCEPROP 2 LAST $SEC 1
J 0
(-7700 6100);
DISPLAY 0.680851 (-7700 6100);
PAINT MONO (-7700 6100);
DISPLAY INVISIBLE (-7700 6100);
FORCEPROP 2 LAST CDS_SEC 1
J 0
(-7700 6100);
DISPLAY 1.021277 (-7700 6100);
DISPLAY INVISIBLE (-7700 6100);
FORCEPROP 1 LASTPIN (-7750 6000) $PN 1
J 0
(-7740 5980);
DISPLAY 0.489362 (-7740 5980);
FORCEPROP 1 LASTPIN (-7750 5800) $PN 2
J 0
(-7740 5780);
DISPLAY 0.489362 (-7740 5780);
FORCEPROP 1 LAST MATERIAL X6S
J 0
(-7700 5800);
DISPLAY 0.489362 (-7700 5800);
PAINT SKYBLUE (-7700 5800);
FORCEPROP 1 LAST TOLERANCE 20%
J 0
(-7700 5850);
DISPLAY 0.489362 (-7700 5850);
PAINT SKYBLUE (-7700 5850);
FORCEPROP 1 LAST VALUE 22UF
J 0
(-7700 5950);
DISPLAY 0.489362 (-7700 5950);
PAINT SKYBLUE (-7700 5950);
FORCEPROP 1 LAST VOLTAGE 4V
J 0
(-7700 5900);
DISPLAY 0.489362 (-7700 5900);
PAINT SKYBLUE (-7700 5900);
FORCEPROP 1 LAST PACK_TYPE C0402
J 0
(-7700 5700);
DISPLAY 0.489362 (-7700 5700);
PAINT SKYBLUE (-7700 5700);
FORCEPROP 2 LAST CDS_LIB pure_quanta
J 0
(-7750 5900);
PAINT MONO (-7750 5900);
DISPLAY INVISIBLE (-7750 5900);
FORCEPROP 1 LAST PATH I85
J 0
(-7700 6050);
DISPLAY 0.978723 (-7700 6050);
PAINT WHITE (-7700 6050);
DISPLAY INVISIBLE (-7700 6050);
FORCEPROP 1 LAST PART_NUMBER CH622KMEB02
J 0
(-7700 5750);
DISPLAY 0.489362 (-7700 5750);
PAINT SKYBLUE (-7700 5750);
DISPLAY INVISIBLE (-7700 5750);
FORCEADD Q_CAP..1
(-7300 5900);
FORCEPROP 1 LAST LOCATION C2555
J 0
(-7250 6000);
DISPLAY 0.489362 (-7250 6000);
PAINT SKYBLUE (-7250 6000);
FORCEPROP 2 LAST $SEC 1
J 0
(-7250 6100);
DISPLAY 0.680851 (-7250 6100);
PAINT MONO (-7250 6100);
DISPLAY INVISIBLE (-7250 6100);
FORCEPROP 2 LAST CDS_SEC 1
J 0
(-7250 6100);
DISPLAY 1.021277 (-7250 6100);
DISPLAY INVISIBLE (-7250 6100);
FORCEPROP 1 LASTPIN (-7300 6000) $PN 1
J 0
(-7290 5980);
DISPLAY 0.489362 (-7290 5980);
FORCEPROP 1 LASTPIN (-7300 5800) $PN 2
J 0
(-7290 5780);
DISPLAY 0.489362 (-7290 5780);
FORCEPROP 1 LAST MATERIAL X6S
J 0
(-7250 5800);
DISPLAY 0.489362 (-7250 5800);
PAINT SKYBLUE (-7250 5800);
FORCEPROP 1 LAST TOLERANCE 20%
J 0
(-7250 5850);
DISPLAY 0.489362 (-7250 5850);
PAINT SKYBLUE (-7250 5850);
FORCEPROP 1 LAST VALUE 22UF
J 0
(-7250 5950);
DISPLAY 0.489362 (-7250 5950);
PAINT SKYBLUE (-7250 5950);
FORCEPROP 1 LAST VOLTAGE 4V
J 0
(-7250 5900);
DISPLAY 0.489362 (-7250 5900);
PAINT SKYBLUE (-7250 5900);
FORCEPROP 1 LAST PACK_TYPE C0402
J 0
(-7250 5700);
DISPLAY 0.489362 (-7250 5700);
PAINT SKYBLUE (-7250 5700);
FORCEPROP 2 LAST CDS_LIB pure_quanta
J 0
(-7300 5900);
PAINT MONO (-7300 5900);
DISPLAY INVISIBLE (-7300 5900);
FORCEPROP 1 LAST PATH I86
J 0
(-7250 6050);
DISPLAY 0.978723 (-7250 6050);
PAINT WHITE (-7250 6050);
DISPLAY INVISIBLE (-7250 6050);
FORCEPROP 1 LAST PART_NUMBER CH622KMEB02
J 0
(-7250 5750);
DISPLAY 0.489362 (-7250 5750);
PAINT SKYBLUE (-7250 5750);
DISPLAY INVISIBLE (-7250 5750);
FORCEADD Q_CAP..1
(-6850 4425);
FORCEPROP 1 LAST LOCATION C2564
J 0
(-6800 4525);
DISPLAY 0.489362 (-6800 4525);
PAINT SKYBLUE (-6800 4525);
FORCEPROP 2 LAST $SEC 1
J 0
(-6800 4625);
DISPLAY 0.680851 (-6800 4625);
PAINT MONO (-6800 4625);
DISPLAY INVISIBLE (-6800 4625);
FORCEPROP 2 LAST CDS_SEC 1
J 0
(-6800 4625);
DISPLAY 1.021277 (-6800 4625);
DISPLAY INVISIBLE (-6800 4625);
FORCEPROP 1 LASTPIN (-6850 4525) $PN 1
J 0
(-6840 4505);
DISPLAY 0.489362 (-6840 4505);
FORCEPROP 1 LASTPIN (-6850 4325) $PN 2
J 0
(-6840 4305);
DISPLAY 0.489362 (-6840 4305);
FORCEPROP 1 LAST MATERIAL X6S
J 0
(-6800 4325);
DISPLAY 0.489362 (-6800 4325);
PAINT SKYBLUE (-6800 4325);
FORCEPROP 1 LAST TOLERANCE 20%
J 0
(-6800 4375);
DISPLAY 0.489362 (-6800 4375);
PAINT SKYBLUE (-6800 4375);
FORCEPROP 1 LAST VALUE 22UF
J 0
(-6800 4475);
DISPLAY 0.489362 (-6800 4475);
PAINT SKYBLUE (-6800 4475);
FORCEPROP 1 LAST VOLTAGE 4V
J 0
(-6800 4425);
DISPLAY 0.489362 (-6800 4425);
PAINT SKYBLUE (-6800 4425);
FORCEPROP 1 LAST PACK_TYPE C0402
J 0
(-6800 4225);
DISPLAY 0.489362 (-6800 4225);
PAINT SKYBLUE (-6800 4225);
FORCEPROP 2 LAST CDS_LIB pure_quanta
J 0
(-6850 4425);
PAINT MONO (-6850 4425);
DISPLAY INVISIBLE (-6850 4425);
FORCEPROP 1 LAST PATH I87
J 0
(-6800 4575);
DISPLAY 0.978723 (-6800 4575);
PAINT WHITE (-6800 4575);
DISPLAY INVISIBLE (-6800 4575);
FORCEPROP 1 LAST PART_NUMBER CH622KMEB02
J 0
(-6800 4275);
DISPLAY 0.489362 (-6800 4275);
PAINT SKYBLUE (-6800 4275);
DISPLAY INVISIBLE (-6800 4275);
FORCEADD Q_CAP..1
(-6850 5150);
FORCEPROP 1 LAST LOCATION C2563
J 0
(-6800 5250);
DISPLAY 0.489362 (-6800 5250);
PAINT SKYBLUE (-6800 5250);
FORCEPROP 2 LAST $SEC 1
J 0
(-6800 5350);
DISPLAY 0.680851 (-6800 5350);
PAINT MONO (-6800 5350);
DISPLAY INVISIBLE (-6800 5350);
FORCEPROP 2 LAST CDS_SEC 1
J 0
(-6800 5350);
DISPLAY 1.021277 (-6800 5350);
DISPLAY INVISIBLE (-6800 5350);
FORCEPROP 1 LASTPIN (-6850 5250) $PN 1
J 0
(-6840 5230);
DISPLAY 0.489362 (-6840 5230);
FORCEPROP 1 LASTPIN (-6850 5050) $PN 2
J 0
(-6840 5030);
DISPLAY 0.489362 (-6840 5030);
FORCEPROP 1 LAST MATERIAL X6S
J 0
(-6800 5050);
DISPLAY 0.489362 (-6800 5050);
PAINT SKYBLUE (-6800 5050);
FORCEPROP 1 LAST TOLERANCE 20%
J 0
(-6800 5100);
DISPLAY 0.489362 (-6800 5100);
PAINT SKYBLUE (-6800 5100);
FORCEPROP 1 LAST VALUE 22UF
J 0
(-6800 5200);
DISPLAY 0.489362 (-6800 5200);
PAINT SKYBLUE (-6800 5200);
FORCEPROP 1 LAST VOLTAGE 4V
J 0
(-6800 5150);
DISPLAY 0.489362 (-6800 5150);
PAINT SKYBLUE (-6800 5150);
FORCEPROP 1 LAST PACK_TYPE C0402
J 0
(-6800 4950);
DISPLAY 0.489362 (-6800 4950);
PAINT SKYBLUE (-6800 4950);
FORCEPROP 2 LAST CDS_LIB pure_quanta
J 0
(-6850 5150);
PAINT MONO (-6850 5150);
DISPLAY INVISIBLE (-6850 5150);
FORCEPROP 1 LAST PATH I88
J 0
(-6800 5300);
DISPLAY 0.978723 (-6800 5300);
PAINT WHITE (-6800 5300);
DISPLAY INVISIBLE (-6800 5300);
FORCEPROP 1 LAST PART_NUMBER CH622KMEB02
J 0
(-6800 5000);
DISPLAY 0.489362 (-6800 5000);
PAINT SKYBLUE (-6800 5000);
DISPLAY INVISIBLE (-6800 5000);
FORCEADD Q_CAP..1
(-6400 4425);
FORCEPROP 1 LAST LOCATION C2571
J 0
(-6350 4525);
DISPLAY 0.489362 (-6350 4525);
PAINT SKYBLUE (-6350 4525);
FORCEPROP 2 LAST $SEC 1
J 0
(-6350 4625);
DISPLAY 0.680851 (-6350 4625);
PAINT MONO (-6350 4625);
DISPLAY INVISIBLE (-6350 4625);
FORCEPROP 2 LAST CDS_SEC 1
J 0
(-6350 4625);
DISPLAY 1.021277 (-6350 4625);
DISPLAY INVISIBLE (-6350 4625);
FORCEPROP 1 LASTPIN (-6400 4525) $PN 1
J 0
(-6390 4505);
DISPLAY 0.489362 (-6390 4505);
FORCEPROP 1 LASTPIN (-6400 4325) $PN 2
J 0
(-6390 4305);
DISPLAY 0.489362 (-6390 4305);
FORCEPROP 1 LAST MATERIAL X6S
J 0
(-6350 4325);
DISPLAY 0.489362 (-6350 4325);
PAINT SKYBLUE (-6350 4325);
FORCEPROP 1 LAST TOLERANCE 20%
J 0
(-6350 4375);
DISPLAY 0.489362 (-6350 4375);
PAINT SKYBLUE (-6350 4375);
FORCEPROP 1 LAST VALUE 22UF
J 0
(-6350 4475);
DISPLAY 0.489362 (-6350 4475);
PAINT SKYBLUE (-6350 4475);
FORCEPROP 1 LAST VOLTAGE 4V
J 0
(-6350 4425);
DISPLAY 0.489362 (-6350 4425);
PAINT SKYBLUE (-6350 4425);
FORCEPROP 1 LAST PACK_TYPE C0402
J 0
(-6350 4225);
DISPLAY 0.489362 (-6350 4225);
PAINT SKYBLUE (-6350 4225);
FORCEPROP 2 LAST CDS_LIB pure_quanta
J 0
(-6400 4425);
PAINT MONO (-6400 4425);
DISPLAY INVISIBLE (-6400 4425);
FORCEPROP 1 LAST PATH I89
J 0
(-6350 4575);
DISPLAY 0.978723 (-6350 4575);
PAINT WHITE (-6350 4575);
DISPLAY INVISIBLE (-6350 4575);
FORCEPROP 1 LAST PART_NUMBER CH622KMEB02
J 0
(-6350 4275);
DISPLAY 0.489362 (-6350 4275);
PAINT SKYBLUE (-6350 4275);
DISPLAY INVISIBLE (-6350 4275);
FORCEADD Q_CAP..1
(-9075 3000);
FORCEPROP 1 LAST LOCATION C2531
J 0
(-9025 3100);
DISPLAY 0.489362 (-9025 3100);
PAINT SKYBLUE (-9025 3100);
FORCEPROP 2 LAST $SEC 1
J 0
(-9025 3200);
DISPLAY 0.680851 (-9025 3200);
PAINT MONO (-9025 3200);
DISPLAY INVISIBLE (-9025 3200);
FORCEPROP 2 LAST CDS_SEC 1
J 0
(-9025 3200);
DISPLAY 1.021277 (-9025 3200);
DISPLAY INVISIBLE (-9025 3200);
FORCEPROP 1 LASTPIN (-9075 3100) $PN 1
J 0
(-9065 3080);
DISPLAY 0.489362 (-9065 3080);
FORCEPROP 1 LASTPIN (-9075 2900) $PN 2
J 0
(-9065 2880);
DISPLAY 0.489362 (-9065 2880);
FORCEPROP 1 LAST MATERIAL X6S
J 0
(-9025 2900);
DISPLAY 0.489362 (-9025 2900);
PAINT SKYBLUE (-9025 2900);
FORCEPROP 1 LAST TOLERANCE 20%
J 0
(-9025 2950);
DISPLAY 0.489362 (-9025 2950);
PAINT SKYBLUE (-9025 2950);
FORCEPROP 1 LAST VALUE 22UF
J 0
(-9025 3050);
DISPLAY 0.489362 (-9025 3050);
PAINT SKYBLUE (-9025 3050);
FORCEPROP 1 LAST VOLTAGE 4V
J 0
(-9025 3000);
DISPLAY 0.489362 (-9025 3000);
PAINT SKYBLUE (-9025 3000);
FORCEPROP 1 LAST PACK_TYPE C0402
J 0
(-9025 2800);
DISPLAY 0.489362 (-9025 2800);
PAINT SKYBLUE (-9025 2800);
FORCEPROP 2 LAST CDS_LIB pure_quanta
J 0
(-9075 3000);
PAINT MONO (-9075 3000);
DISPLAY INVISIBLE (-9075 3000);
FORCEPROP 1 LAST PATH I9
J 0
(-9025 3150);
DISPLAY 0.978723 (-9025 3150);
PAINT WHITE (-9025 3150);
DISPLAY INVISIBLE (-9025 3150);
FORCEPROP 1 LAST PART_NUMBER CH622KMEB02
J 0
(-9025 2850);
DISPLAY 0.489362 (-9025 2850);
PAINT SKYBLUE (-9025 2850);
DISPLAY INVISIBLE (-9025 2850);
FORCEADD Q_CAP..1
(-6400 5150);
FORCEPROP 1 LAST LOCATION C2570
J 0
(-6350 5250);
DISPLAY 0.489362 (-6350 5250);
PAINT SKYBLUE (-6350 5250);
FORCEPROP 2 LAST $SEC 1
J 0
(-6350 5350);
DISPLAY 0.680851 (-6350 5350);
PAINT MONO (-6350 5350);
DISPLAY INVISIBLE (-6350 5350);
FORCEPROP 2 LAST CDS_SEC 1
J 0
(-6350 5350);
DISPLAY 1.021277 (-6350 5350);
DISPLAY INVISIBLE (-6350 5350);
FORCEPROP 1 LASTPIN (-6400 5250) $PN 1
J 0
(-6390 5230);
DISPLAY 0.489362 (-6390 5230);
FORCEPROP 1 LASTPIN (-6400 5050) $PN 2
J 0
(-6390 5030);
DISPLAY 0.489362 (-6390 5030);
FORCEPROP 1 LAST MATERIAL X6S
J 0
(-6350 5050);
DISPLAY 0.489362 (-6350 5050);
PAINT SKYBLUE (-6350 5050);
FORCEPROP 1 LAST TOLERANCE 20%
J 0
(-6350 5100);
DISPLAY 0.489362 (-6350 5100);
PAINT SKYBLUE (-6350 5100);
FORCEPROP 1 LAST VALUE 22UF
J 0
(-6350 5200);
DISPLAY 0.489362 (-6350 5200);
PAINT SKYBLUE (-6350 5200);
FORCEPROP 1 LAST VOLTAGE 4V
J 0
(-6350 5150);
DISPLAY 0.489362 (-6350 5150);
PAINT SKYBLUE (-6350 5150);
FORCEPROP 1 LAST PACK_TYPE C0402
J 0
(-6350 4950);
DISPLAY 0.489362 (-6350 4950);
PAINT SKYBLUE (-6350 4950);
FORCEPROP 2 LAST CDS_LIB pure_quanta
J 0
(-6400 5150);
PAINT MONO (-6400 5150);
DISPLAY INVISIBLE (-6400 5150);
FORCEPROP 1 LAST PATH I90
J 0
(-6350 5300);
DISPLAY 0.978723 (-6350 5300);
PAINT WHITE (-6350 5300);
DISPLAY INVISIBLE (-6350 5300);
FORCEPROP 1 LAST PART_NUMBER CH622KMEB02
J 0
(-6350 5000);
DISPLAY 0.489362 (-6350 5000);
PAINT SKYBLUE (-6350 5000);
DISPLAY INVISIBLE (-6350 5000);
FORCEADD Q_CAP..1
(-6850 5900);
FORCEPROP 1 LAST LOCATION C2562
J 0
(-6800 6000);
DISPLAY 0.489362 (-6800 6000);
PAINT SKYBLUE (-6800 6000);
FORCEPROP 2 LAST $SEC 1
J 0
(-6800 6100);
DISPLAY 0.680851 (-6800 6100);
PAINT MONO (-6800 6100);
DISPLAY INVISIBLE (-6800 6100);
FORCEPROP 2 LAST CDS_SEC 1
J 0
(-6800 6100);
DISPLAY 1.021277 (-6800 6100);
DISPLAY INVISIBLE (-6800 6100);
FORCEPROP 1 LASTPIN (-6850 6000) $PN 1
J 0
(-6840 5980);
DISPLAY 0.489362 (-6840 5980);
FORCEPROP 1 LASTPIN (-6850 5800) $PN 2
J 0
(-6840 5780);
DISPLAY 0.489362 (-6840 5780);
FORCEPROP 1 LAST MATERIAL X6S
J 0
(-6800 5800);
DISPLAY 0.489362 (-6800 5800);
PAINT SKYBLUE (-6800 5800);
FORCEPROP 1 LAST TOLERANCE 20%
J 0
(-6800 5850);
DISPLAY 0.489362 (-6800 5850);
PAINT SKYBLUE (-6800 5850);
FORCEPROP 1 LAST VALUE 22UF
J 0
(-6800 5950);
DISPLAY 0.489362 (-6800 5950);
PAINT SKYBLUE (-6800 5950);
FORCEPROP 1 LAST VOLTAGE 4V
J 0
(-6800 5900);
DISPLAY 0.489362 (-6800 5900);
PAINT SKYBLUE (-6800 5900);
FORCEPROP 1 LAST PACK_TYPE C0402
J 0
(-6800 5700);
DISPLAY 0.489362 (-6800 5700);
PAINT SKYBLUE (-6800 5700);
FORCEPROP 2 LAST CDS_LIB pure_quanta
J 0
(-6850 5900);
PAINT MONO (-6850 5900);
DISPLAY INVISIBLE (-6850 5900);
FORCEPROP 1 LAST PATH I91
J 0
(-6800 6050);
DISPLAY 0.978723 (-6800 6050);
PAINT WHITE (-6800 6050);
DISPLAY INVISIBLE (-6800 6050);
FORCEPROP 1 LAST PART_NUMBER CH622KMEB02
J 0
(-6800 5750);
DISPLAY 0.489362 (-6800 5750);
PAINT SKYBLUE (-6800 5750);
DISPLAY INVISIBLE (-6800 5750);
FORCEADD Q_CAP..1
(-6400 5900);
FORCEPROP 1 LAST LOCATION C2569
J 0
(-6350 6000);
DISPLAY 0.489362 (-6350 6000);
PAINT SKYBLUE (-6350 6000);
FORCEPROP 2 LAST $SEC 1
J 0
(-6350 6100);
DISPLAY 0.680851 (-6350 6100);
PAINT MONO (-6350 6100);
DISPLAY INVISIBLE (-6350 6100);
FORCEPROP 2 LAST CDS_SEC 1
J 0
(-6350 6100);
DISPLAY 1.021277 (-6350 6100);
DISPLAY INVISIBLE (-6350 6100);
FORCEPROP 1 LASTPIN (-6400 6000) $PN 1
J 0
(-6390 5980);
DISPLAY 0.489362 (-6390 5980);
FORCEPROP 1 LASTPIN (-6400 5800) $PN 2
J 0
(-6390 5780);
DISPLAY 0.489362 (-6390 5780);
FORCEPROP 1 LAST MATERIAL X6S
J 0
(-6350 5800);
DISPLAY 0.489362 (-6350 5800);
PAINT SKYBLUE (-6350 5800);
FORCEPROP 1 LAST TOLERANCE 20%
J 0
(-6350 5850);
DISPLAY 0.489362 (-6350 5850);
PAINT SKYBLUE (-6350 5850);
FORCEPROP 1 LAST VALUE 22UF
J 0
(-6350 5950);
DISPLAY 0.489362 (-6350 5950);
PAINT SKYBLUE (-6350 5950);
FORCEPROP 1 LAST VOLTAGE 4V
J 0
(-6350 5900);
DISPLAY 0.489362 (-6350 5900);
PAINT SKYBLUE (-6350 5900);
FORCEPROP 1 LAST PACK_TYPE C0402
J 0
(-6350 5700);
DISPLAY 0.489362 (-6350 5700);
PAINT SKYBLUE (-6350 5700);
FORCEPROP 2 LAST CDS_LIB pure_quanta
J 0
(-6400 5900);
PAINT MONO (-6400 5900);
DISPLAY INVISIBLE (-6400 5900);
FORCEPROP 1 LAST PATH I92
J 0
(-6350 6050);
DISPLAY 0.978723 (-6350 6050);
PAINT WHITE (-6350 6050);
DISPLAY INVISIBLE (-6350 6050);
FORCEPROP 1 LAST PART_NUMBER CH622KMEB02
J 0
(-6350 5750);
DISPLAY 0.489362 (-6350 5750);
PAINT SKYBLUE (-6350 5750);
DISPLAY INVISIBLE (-6350 5750);
FORCEADD Q_CAP..1
(-5950 4425);
FORCEPROP 1 LAST LOCATION C2578
J 0
(-5900 4525);
DISPLAY 0.489362 (-5900 4525);
PAINT SKYBLUE (-5900 4525);
FORCEPROP 2 LAST $SEC 1
J 0
(-5900 4625);
DISPLAY 0.680851 (-5900 4625);
PAINT MONO (-5900 4625);
DISPLAY INVISIBLE (-5900 4625);
FORCEPROP 2 LAST CDS_SEC 1
J 0
(-5900 4625);
DISPLAY 1.021277 (-5900 4625);
DISPLAY INVISIBLE (-5900 4625);
FORCEPROP 1 LASTPIN (-5950 4525) $PN 1
J 0
(-5940 4505);
DISPLAY 0.489362 (-5940 4505);
FORCEPROP 1 LASTPIN (-5950 4325) $PN 2
J 0
(-5940 4305);
DISPLAY 0.489362 (-5940 4305);
FORCEPROP 1 LAST MATERIAL X6S
J 0
(-5900 4325);
DISPLAY 0.489362 (-5900 4325);
PAINT SKYBLUE (-5900 4325);
FORCEPROP 1 LAST TOLERANCE 20%
J 0
(-5900 4375);
DISPLAY 0.489362 (-5900 4375);
PAINT SKYBLUE (-5900 4375);
FORCEPROP 1 LAST VALUE 22UF
J 0
(-5900 4475);
DISPLAY 0.489362 (-5900 4475);
PAINT SKYBLUE (-5900 4475);
FORCEPROP 1 LAST VOLTAGE 4V
J 0
(-5900 4425);
DISPLAY 0.489362 (-5900 4425);
PAINT SKYBLUE (-5900 4425);
FORCEPROP 1 LAST PACK_TYPE C0402
J 0
(-5900 4225);
DISPLAY 0.489362 (-5900 4225);
PAINT SKYBLUE (-5900 4225);
FORCEPROP 2 LAST CDS_LIB pure_quanta
J 0
(-5950 4425);
PAINT MONO (-5950 4425);
DISPLAY INVISIBLE (-5950 4425);
FORCEPROP 1 LAST PATH I93
J 0
(-5900 4575);
DISPLAY 0.978723 (-5900 4575);
PAINT WHITE (-5900 4575);
DISPLAY INVISIBLE (-5900 4575);
FORCEPROP 1 LAST PART_NUMBER CH622KMEB02
J 0
(-5900 4275);
DISPLAY 0.489362 (-5900 4275);
PAINT SKYBLUE (-5900 4275);
DISPLAY INVISIBLE (-5900 4275);
FORCEADD Q_CAP..1
(-5950 5150);
FORCEPROP 1 LAST LOCATION C2577
J 0
(-5900 5250);
DISPLAY 0.489362 (-5900 5250);
PAINT SKYBLUE (-5900 5250);
FORCEPROP 2 LAST $SEC 1
J 0
(-5900 5350);
DISPLAY 0.680851 (-5900 5350);
PAINT MONO (-5900 5350);
DISPLAY INVISIBLE (-5900 5350);
FORCEPROP 2 LAST CDS_SEC 1
J 0
(-5900 5350);
DISPLAY 1.021277 (-5900 5350);
DISPLAY INVISIBLE (-5900 5350);
FORCEPROP 1 LASTPIN (-5950 5250) $PN 1
J 0
(-5940 5230);
DISPLAY 0.489362 (-5940 5230);
FORCEPROP 1 LASTPIN (-5950 5050) $PN 2
J 0
(-5940 5030);
DISPLAY 0.489362 (-5940 5030);
FORCEPROP 1 LAST MATERIAL X6S
J 0
(-5900 5050);
DISPLAY 0.489362 (-5900 5050);
PAINT SKYBLUE (-5900 5050);
FORCEPROP 1 LAST TOLERANCE 20%
J 0
(-5900 5100);
DISPLAY 0.489362 (-5900 5100);
PAINT SKYBLUE (-5900 5100);
FORCEPROP 1 LAST VALUE 22UF
J 0
(-5900 5200);
DISPLAY 0.489362 (-5900 5200);
PAINT SKYBLUE (-5900 5200);
FORCEPROP 1 LAST VOLTAGE 4V
J 0
(-5900 5150);
DISPLAY 0.489362 (-5900 5150);
PAINT SKYBLUE (-5900 5150);
FORCEPROP 1 LAST PACK_TYPE C0402
J 0
(-5900 4950);
DISPLAY 0.489362 (-5900 4950);
PAINT SKYBLUE (-5900 4950);
FORCEPROP 2 LAST CDS_LIB pure_quanta
J 0
(-5950 5150);
PAINT MONO (-5950 5150);
DISPLAY INVISIBLE (-5950 5150);
FORCEPROP 1 LAST PATH I94
J 0
(-5900 5300);
DISPLAY 0.978723 (-5900 5300);
PAINT WHITE (-5900 5300);
DISPLAY INVISIBLE (-5900 5300);
FORCEPROP 1 LAST PART_NUMBER CH622KMEB02
J 0
(-5900 5000);
DISPLAY 0.489362 (-5900 5000);
PAINT SKYBLUE (-5900 5000);
DISPLAY INVISIBLE (-5900 5000);
FORCEADD Q_CAP..1
(-5500 4425);
FORCEPROP 1 LAST LOCATION C2585
J 0
(-5450 4525);
DISPLAY 0.489362 (-5450 4525);
PAINT SKYBLUE (-5450 4525);
FORCEPROP 2 LAST $SEC 1
J 0
(-5450 4625);
DISPLAY 0.680851 (-5450 4625);
PAINT MONO (-5450 4625);
DISPLAY INVISIBLE (-5450 4625);
FORCEPROP 2 LAST CDS_SEC 1
J 0
(-5450 4625);
DISPLAY 1.021277 (-5450 4625);
DISPLAY INVISIBLE (-5450 4625);
FORCEPROP 1 LASTPIN (-5500 4525) $PN 1
J 0
(-5490 4505);
DISPLAY 0.489362 (-5490 4505);
FORCEPROP 1 LASTPIN (-5500 4325) $PN 2
J 0
(-5490 4305);
DISPLAY 0.489362 (-5490 4305);
FORCEPROP 1 LAST MATERIAL X6S
J 0
(-5450 4325);
DISPLAY 0.489362 (-5450 4325);
PAINT SKYBLUE (-5450 4325);
FORCEPROP 1 LAST TOLERANCE 20%
J 0
(-5450 4375);
DISPLAY 0.489362 (-5450 4375);
PAINT SKYBLUE (-5450 4375);
FORCEPROP 1 LAST VALUE 22UF
J 0
(-5450 4475);
DISPLAY 0.489362 (-5450 4475);
PAINT SKYBLUE (-5450 4475);
FORCEPROP 1 LAST VOLTAGE 4V
J 0
(-5450 4425);
DISPLAY 0.489362 (-5450 4425);
PAINT SKYBLUE (-5450 4425);
FORCEPROP 1 LAST PACK_TYPE C0402
J 0
(-5450 4225);
DISPLAY 0.489362 (-5450 4225);
PAINT SKYBLUE (-5450 4225);
FORCEPROP 2 LAST CDS_LIB pure_quanta
J 0
(-5500 4425);
PAINT MONO (-5500 4425);
DISPLAY INVISIBLE (-5500 4425);
FORCEPROP 1 LAST PATH I95
J 0
(-5450 4575);
DISPLAY 0.978723 (-5450 4575);
PAINT WHITE (-5450 4575);
DISPLAY INVISIBLE (-5450 4575);
FORCEPROP 1 LAST PART_NUMBER CH622KMEB02
J 0
(-5450 4275);
DISPLAY 0.489362 (-5450 4275);
PAINT SKYBLUE (-5450 4275);
DISPLAY INVISIBLE (-5450 4275);
FORCEADD Q_CAP..1
(-5500 5150);
FORCEPROP 1 LAST LOCATION C2584
J 0
(-5450 5250);
DISPLAY 0.489362 (-5450 5250);
PAINT SKYBLUE (-5450 5250);
FORCEPROP 2 LAST $SEC 1
J 0
(-5450 5350);
DISPLAY 0.680851 (-5450 5350);
PAINT MONO (-5450 5350);
DISPLAY INVISIBLE (-5450 5350);
FORCEPROP 2 LAST CDS_SEC 1
J 0
(-5450 5350);
DISPLAY 1.021277 (-5450 5350);
DISPLAY INVISIBLE (-5450 5350);
FORCEPROP 1 LASTPIN (-5500 5250) $PN 1
J 0
(-5490 5230);
DISPLAY 0.489362 (-5490 5230);
FORCEPROP 1 LASTPIN (-5500 5050) $PN 2
J 0
(-5490 5030);
DISPLAY 0.489362 (-5490 5030);
FORCEPROP 1 LAST MATERIAL X6S
J 0
(-5450 5050);
DISPLAY 0.489362 (-5450 5050);
PAINT SKYBLUE (-5450 5050);
FORCEPROP 1 LAST TOLERANCE 20%
J 0
(-5450 5100);
DISPLAY 0.489362 (-5450 5100);
PAINT SKYBLUE (-5450 5100);
FORCEPROP 1 LAST VALUE 22UF
J 0
(-5450 5200);
DISPLAY 0.489362 (-5450 5200);
PAINT SKYBLUE (-5450 5200);
FORCEPROP 1 LAST VOLTAGE 4V
J 0
(-5450 5150);
DISPLAY 0.489362 (-5450 5150);
PAINT SKYBLUE (-5450 5150);
FORCEPROP 1 LAST PACK_TYPE C0402
J 0
(-5450 4950);
DISPLAY 0.489362 (-5450 4950);
PAINT SKYBLUE (-5450 4950);
FORCEPROP 2 LAST CDS_LIB pure_quanta
J 0
(-5500 5150);
PAINT MONO (-5500 5150);
DISPLAY INVISIBLE (-5500 5150);
FORCEPROP 1 LAST PATH I96
J 0
(-5450 5300);
DISPLAY 0.978723 (-5450 5300);
PAINT WHITE (-5450 5300);
DISPLAY INVISIBLE (-5450 5300);
FORCEPROP 1 LAST PART_NUMBER CH622KMEB02
J 0
(-5450 5000);
DISPLAY 0.489362 (-5450 5000);
PAINT SKYBLUE (-5450 5000);
DISPLAY INVISIBLE (-5450 5000);
FORCEADD Q_CAP..1
(-5950 5900);
FORCEPROP 1 LAST LOCATION C2576
J 0
(-5900 6000);
DISPLAY 0.489362 (-5900 6000);
PAINT SKYBLUE (-5900 6000);
FORCEPROP 2 LAST $SEC 1
J 0
(-5900 6100);
DISPLAY 0.680851 (-5900 6100);
PAINT MONO (-5900 6100);
DISPLAY INVISIBLE (-5900 6100);
FORCEPROP 2 LAST CDS_SEC 1
J 0
(-5900 6100);
DISPLAY 1.021277 (-5900 6100);
DISPLAY INVISIBLE (-5900 6100);
FORCEPROP 1 LASTPIN (-5950 6000) $PN 1
J 0
(-5940 5980);
DISPLAY 0.489362 (-5940 5980);
FORCEPROP 1 LASTPIN (-5950 5800) $PN 2
J 0
(-5940 5780);
DISPLAY 0.489362 (-5940 5780);
FORCEPROP 1 LAST MATERIAL X6S
J 0
(-5900 5800);
DISPLAY 0.489362 (-5900 5800);
PAINT SKYBLUE (-5900 5800);
FORCEPROP 1 LAST TOLERANCE 20%
J 0
(-5900 5850);
DISPLAY 0.489362 (-5900 5850);
PAINT SKYBLUE (-5900 5850);
FORCEPROP 1 LAST VALUE 22UF
J 0
(-5900 5950);
DISPLAY 0.489362 (-5900 5950);
PAINT SKYBLUE (-5900 5950);
FORCEPROP 1 LAST VOLTAGE 4V
J 0
(-5900 5900);
DISPLAY 0.489362 (-5900 5900);
PAINT SKYBLUE (-5900 5900);
FORCEPROP 1 LAST PACK_TYPE C0402
J 0
(-5900 5700);
DISPLAY 0.489362 (-5900 5700);
PAINT SKYBLUE (-5900 5700);
FORCEPROP 2 LAST CDS_LIB pure_quanta
J 0
(-5950 5900);
PAINT MONO (-5950 5900);
DISPLAY INVISIBLE (-5950 5900);
FORCEPROP 1 LAST PATH I97
J 0
(-5900 6050);
DISPLAY 0.978723 (-5900 6050);
PAINT WHITE (-5900 6050);
DISPLAY INVISIBLE (-5900 6050);
FORCEPROP 1 LAST PART_NUMBER CH622KMEB02
J 0
(-5900 5750);
DISPLAY 0.489362 (-5900 5750);
PAINT SKYBLUE (-5900 5750);
DISPLAY INVISIBLE (-5900 5750);
FORCEADD Q_CAP..1
(-5500 5900);
FORCEPROP 1 LAST LOCATION C2583
J 0
(-5450 6000);
DISPLAY 0.489362 (-5450 6000);
PAINT SKYBLUE (-5450 6000);
FORCEPROP 2 LAST $SEC 1
J 0
(-5450 6100);
DISPLAY 0.680851 (-5450 6100);
PAINT MONO (-5450 6100);
DISPLAY INVISIBLE (-5450 6100);
FORCEPROP 2 LAST CDS_SEC 1
J 0
(-5450 6100);
DISPLAY 1.021277 (-5450 6100);
DISPLAY INVISIBLE (-5450 6100);
FORCEPROP 1 LASTPIN (-5500 6000) $PN 1
J 0
(-5490 5980);
DISPLAY 0.489362 (-5490 5980);
FORCEPROP 1 LASTPIN (-5500 5800) $PN 2
J 0
(-5490 5780);
DISPLAY 0.489362 (-5490 5780);
FORCEPROP 1 LAST MATERIAL X6S
J 0
(-5450 5800);
DISPLAY 0.489362 (-5450 5800);
PAINT SKYBLUE (-5450 5800);
FORCEPROP 1 LAST TOLERANCE 20%
J 0
(-5450 5850);
DISPLAY 0.489362 (-5450 5850);
PAINT SKYBLUE (-5450 5850);
FORCEPROP 1 LAST VALUE 22UF
J 0
(-5450 5950);
DISPLAY 0.489362 (-5450 5950);
PAINT SKYBLUE (-5450 5950);
FORCEPROP 1 LAST VOLTAGE 4V
J 0
(-5450 5900);
DISPLAY 0.489362 (-5450 5900);
PAINT SKYBLUE (-5450 5900);
FORCEPROP 1 LAST PACK_TYPE C0402
J 0
(-5450 5700);
DISPLAY 0.489362 (-5450 5700);
PAINT SKYBLUE (-5450 5700);
FORCEPROP 2 LAST CDS_LIB pure_quanta
J 0
(-5500 5900);
PAINT MONO (-5500 5900);
DISPLAY INVISIBLE (-5500 5900);
FORCEPROP 1 LAST PATH I98
J 0
(-5450 6050);
DISPLAY 0.978723 (-5450 6050);
PAINT WHITE (-5450 6050);
DISPLAY INVISIBLE (-5450 6050);
FORCEPROP 1 LAST PART_NUMBER CH622KMEB02
J 0
(-5450 5750);
DISPLAY 0.489362 (-5450 5750);
PAINT SKYBLUE (-5450 5750);
DISPLAY INVISIBLE (-5450 5750);
FORCEADD Q_CAP..1
(-5100 4425);
FORCEPROP 1 LAST LOCATION C2592
J 0
(-5050 4525);
DISPLAY 0.489362 (-5050 4525);
PAINT SKYBLUE (-5050 4525);
FORCEPROP 2 LAST $SEC 1
J 0
(-5050 4625);
DISPLAY 0.680851 (-5050 4625);
PAINT MONO (-5050 4625);
DISPLAY INVISIBLE (-5050 4625);
FORCEPROP 2 LAST CDS_SEC 1
J 0
(-5050 4625);
DISPLAY 1.021277 (-5050 4625);
DISPLAY INVISIBLE (-5050 4625);
FORCEPROP 1 LASTPIN (-5100 4525) $PN 1
J 0
(-5090 4505);
DISPLAY 0.489362 (-5090 4505);
FORCEPROP 1 LASTPIN (-5100 4325) $PN 2
J 0
(-5090 4305);
DISPLAY 0.489362 (-5090 4305);
FORCEPROP 1 LAST MATERIAL X6S
J 0
(-5050 4325);
DISPLAY 0.489362 (-5050 4325);
PAINT SKYBLUE (-5050 4325);
FORCEPROP 1 LAST TOLERANCE 20%
J 0
(-5050 4375);
DISPLAY 0.489362 (-5050 4375);
PAINT SKYBLUE (-5050 4375);
FORCEPROP 1 LAST VALUE 22UF
J 0
(-5050 4475);
DISPLAY 0.489362 (-5050 4475);
PAINT SKYBLUE (-5050 4475);
FORCEPROP 1 LAST VOLTAGE 4V
J 0
(-5050 4425);
DISPLAY 0.489362 (-5050 4425);
PAINT SKYBLUE (-5050 4425);
FORCEPROP 1 LAST PACK_TYPE C0402
J 0
(-5050 4225);
DISPLAY 0.489362 (-5050 4225);
PAINT SKYBLUE (-5050 4225);
FORCEPROP 2 LAST CDS_LIB pure_quanta
J 0
(-5100 4425);
PAINT MONO (-5100 4425);
DISPLAY INVISIBLE (-5100 4425);
FORCEPROP 1 LAST PATH I99
J 0
(-5050 4575);
DISPLAY 0.978723 (-5050 4575);
PAINT WHITE (-5050 4575);
DISPLAY INVISIBLE (-5050 4575);
FORCEPROP 1 LAST PART_NUMBER CH622KMEB02
J 0
(-5050 4275);
DISPLAY 0.489362 (-5050 4275);
PAINT SKYBLUE (-5050 4275);
DISPLAY INVISIBLE (-5050 4275);
FORCEADD QUANTA_TITLE_BLOCK_C..1
(0 0);
FORCEPROP 0 LAST CDS_CON_LAST_MODIFIED Thu Sep 14 16:12:03 2023
J 0
(-1885 15);
DISPLAY INVISIBLE (-1885 15);
FORCEPROP 1 LAST CUSTOM_TXT_CDS <CON_LAST_MODIFIED>
J 0
(-1885 15);
DISPLAY 0.978723 (-1885 15);
FORCEPROP 2 LAST CUSTOM_TXT_CDS <XR_PAGE_TITLE>
J 0
(-7890 5250);
DISPLAY 0.638298 (-7890 5250);
PAINT PINK (-7890 5250);
DISPLAY INVISIBLE (-7890 5250);
FORCEPROP 1 LAST CUSTOM_TXT_CDS <NAME_2>
J 0
(-3175 50);
FORCEPROP 1 LAST CUSTOM_TXT_CDS <NAME_1>
J 0
(-3175 175);
FORCEPROP 1 LAST CUSTOM_TXT_CDS <Q_NUMBER>
J 0
(-1403 103);
DISPLAY 1.212766 (-1403 103);
FORCEPROP 1 LAST CUSTOM_TXT_CDS <Q_PROJ>
J 0
(-2382 102);
DISPLAY 1.212766 (-2382 102);
FORCEPROP 1 LAST CUSTOM_TXT_CDS <Q_REV>
J 0
(-184 103);
DISPLAY 1.212766 (-184 103);
FORCEPROP 1 LAST CUSTOM_TXT_CDS <CON_PAGE_NUM> OF <CON_TOTAL_PAGES>
J 0
(-446 18);
DISPLAY 0.978723 (-446 18);
FORCEPROP 1 LAST Q_TITLE CPU0 CAVITY BOT DECOUPLING CAPS 2/3
J 0
(-9275 50);
DISPLAY 2.446809 (-9275 50);
PAINT GREEN (-9275 50);
FORCEPROP 2 LAST PAGE_BORDER TRUE
J 0
(-7890 5250);
DISPLAY 0.638298 (-7890 5250);
PAINT PINK (-7890 5250);
DISPLAY INVISIBLE (-7890 5250);
FORCEPROP 2 LAST CDS_LIB pure_quanta
J 0
(0 0);
DISPLAY INVISIBLE (0 0);
FORCEPROP 1 LAST CDS_LMAN_SYM_OUTLINE -9475,6775,100,-125
J 0
(0 0);
DISPLAY 0.468085 (0 0);
PAINT GREEN (0 0);
DISPLAY INVISIBLE (0 0);
FORCEPROP 2 LAST CDS_XR_PAGE_TITLE CR-70 : @T6G_MB_LIB.T6G(SCH_1):PAGE70
J 0
(-7890 5250);
DISPLAY 0.638298 (-7890 5250);
PAINT PINK (-7890 5250);
DISPLAY INVISIBLE (-7890 5250);
FORCEPROP 1 LAST Q_DEPT BU9
J 1
(-3763 49);
DISPLAY 1.957447 (-3763 49);
PAINT GREEN (-3763 49);
DISPLAY INVISIBLE (-3763 49);
FORCEPROP 1 LAST COMMENT_BODY TRUE
J 0
(12 -13);
DISPLAY 0.978723 (12 -13);
PAINT GREEN (12 -13);
DISPLAY INVISIBLE (12 -13);
WIRE 16 -1 (-8175 650)(-8625 650);
WIRE 16 -1 (-7725 650)(-8175 650);
WIRE 16 -1 (-8175 650)(-8175 775);
WIRE 16 -1 (-8625 650)(-8625 775);
WIRE 16 -1 (-8625 650)(-9075 650);
WIRE 16 -1 (-9075 650)(-9075 775);
WIRE 16 -1 (-7275 650)(-7725 650);
WIRE 16 -1 (-7725 650)(-7725 775);
WIRE 16 -1 (-6825 650)(-7275 650);
WIRE 16 -1 (-7275 650)(-7275 775);
WIRE 16 -1 (-6375 650)(-6825 650);
WIRE 16 -1 (-6825 650)(-6825 775);
WIRE 16 -1 (-6375 650)(-6375 775);
WIRE 16 -1 (-6375 550)(-6375 650);
WIRE 16 -1 (-7725 1750)(-8175 1750);
WIRE 16 -1 (-7275 1750)(-7725 1750);
WIRE 16 -1 (-7725 1675)(-7725 1750);
WIRE 16 -1 (-8175 1750)(-8175 1675);
WIRE 16 -1 (-8175 1750)(-8625 1750);
WIRE 16 -1 (-8625 1675)(-8625 1750);
WIRE 16 -1 (-8625 1750)(-9075 1750);
WIRE 16 -1 (-6825 1750)(-7275 1750);
WIRE 16 -1 (-7275 1675)(-7275 1750);
WIRE 16 -1 (-6375 1750)(-6825 1750);
WIRE 16 -1 (-6825 1750)(-6825 1675);
WIRE 16 -1 (-9075 1750)(-9075 1800);
WIRE 16 -1 (-9075 1750)(-9075 1675);
WIRE 16 -1 (-5925 1750)(-6375 1750);
WIRE 16 -1 (-6375 1675)(-6375 1750);
WIRE 16 -1 (-5475 1750)(-5925 1750);
WIRE 16 -1 (-5925 1675)(-5925 1750);
WIRE 16 -1 (-5075 1750)(-5475 1750);
WIRE 16 -1 (-5475 1750)(-5475 1675);
WIRE 16 -1 (-5075 1675)(-5075 1750);
WIRE 16 -1 (-8175 1350)(-8625 1350);
WIRE 16 -1 (-7725 1350)(-8175 1350);
WIRE 16 -1 (-8175 1350)(-8175 1475);
WIRE 16 -1 (-8625 1350)(-8625 1475);
WIRE 16 -1 (-8625 1350)(-9075 1350);
WIRE 16 -1 (-9075 1350)(-9075 1475);
WIRE 16 -1 (-7275 1350)(-7725 1350);
WIRE 16 -1 (-7725 1350)(-7725 1475);
WIRE 16 -1 (-6825 1350)(-7275 1350);
WIRE 16 -1 (-7275 1350)(-7275 1475);
WIRE 16 -1 (-6375 1350)(-6825 1350);
WIRE 16 -1 (-6825 1350)(-6825 1475);
WIRE 16 -1 (-5925 1350)(-6375 1350);
WIRE 16 -1 (-6375 1350)(-6375 1475);
WIRE 16 -1 (-5475 1350)(-5925 1350);
WIRE 16 -1 (-5925 1350)(-5925 1475);
WIRE 16 -1 (-5075 1350)(-5475 1350);
WIRE 16 -1 (-5475 1350)(-5475 1475);
WIRE 16 -1 (-5075 1350)(-5075 1475);
WIRE 16 -1 (-5075 1250)(-5075 1350);
WIRE 16 -1 (-8625 975)(-8625 1050);
WIRE 16 -1 (-8175 1050)(-8625 1050);
WIRE 16 -1 (-8625 1050)(-9075 1050);
WIRE 16 -1 (-9075 1050)(-9075 1100);
WIRE 16 -1 (-9075 1050)(-9075 975);
WIRE 16 -1 (-7725 1050)(-8175 1050);
WIRE 16 -1 (-8175 1050)(-8175 975);
WIRE 16 -1 (-7275 1050)(-7725 1050);
WIRE 16 -1 (-7725 975)(-7725 1050);
WIRE 16 -1 (-6825 1050)(-7275 1050);
WIRE 16 -1 (-7275 975)(-7275 1050);
WIRE 16 -1 (-6375 1050)(-6825 1050);
WIRE 16 -1 (-6825 1050)(-6825 975);
WIRE 16 -1 (-6375 975)(-6375 1050);
WIRE 16 -1 (-8175 2775)(-8625 2775);
WIRE 16 -1 (-7725 2775)(-8175 2775);
WIRE 16 -1 (-8175 2775)(-8175 2900);
WIRE 16 -1 (-8625 2775)(-8625 2900);
WIRE 16 -1 (-8625 2775)(-9075 2775);
WIRE 16 -1 (-9075 2775)(-9075 2900);
WIRE 16 -1 (-7275 2775)(-7725 2775);
WIRE 16 -1 (-7725 2775)(-7725 2900);
WIRE 16 -1 (-6825 2775)(-7275 2775);
WIRE 16 -1 (-7275 2775)(-7275 2900);
WIRE 16 -1 (-6375 2775)(-6825 2775);
WIRE 16 -1 (-6825 2775)(-6825 2900);
WIRE 16 -1 (-5925 2775)(-6375 2775);
WIRE 16 -1 (-6375 2775)(-6375 2900);
WIRE 16 -1 (-5475 2775)(-5925 2775);
WIRE 16 -1 (-5925 2775)(-5925 2900);
WIRE 16 -1 (-5075 2775)(-5475 2775);
WIRE 16 -1 (-5475 2775)(-5475 2900);
WIRE 16 -1 (-5075 2775)(-5075 2900);
WIRE 16 -1 (-5075 2675)(-5075 2775);
WIRE 16 -1 (-7725 2475)(-8175 2475);
WIRE 16 -1 (-7275 2475)(-7725 2475);
WIRE 16 -1 (-7725 2400)(-7725 2475);
WIRE 16 -1 (-8175 2475)(-8175 2400);
WIRE 16 -1 (-8175 2475)(-8625 2475);
WIRE 16 -1 (-8625 2400)(-8625 2475);
WIRE 16 -1 (-8625 2475)(-9075 2475);
WIRE 16 -1 (-6825 2475)(-7275 2475);
WIRE 16 -1 (-7275 2400)(-7275 2475);
WIRE 16 -1 (-6375 2475)(-6825 2475);
WIRE 16 -1 (-6825 2475)(-6825 2400);
WIRE 16 -1 (-9075 2475)(-9075 2400);
WIRE 16 -1 (-9075 2475)(-9075 2525);
WIRE 16 -1 (-5925 2475)(-6375 2475);
WIRE 16 -1 (-6375 2400)(-6375 2475);
WIRE 16 -1 (-5475 2475)(-5925 2475);
WIRE 16 -1 (-5925 2400)(-5925 2475);
WIRE 16 -1 (-5075 2475)(-5475 2475);
WIRE 16 -1 (-5475 2475)(-5475 2400);
WIRE 16 -1 (-5075 2400)(-5075 2475);
WIRE 16 -1 (-8175 2075)(-8625 2075);
WIRE 16 -1 (-7725 2075)(-8175 2075);
WIRE 16 -1 (-8175 2075)(-8175 2200);
WIRE 16 -1 (-8625 2075)(-8625 2200);
WIRE 16 -1 (-8625 2075)(-9075 2075);
WIRE 16 -1 (-9075 2075)(-9075 2200);
WIRE 16 -1 (-7275 2075)(-7725 2075);
WIRE 16 -1 (-7725 2075)(-7725 2200);
WIRE 16 -1 (-6825 2075)(-7275 2075);
WIRE 16 -1 (-7275 2075)(-7275 2200);
WIRE 16 -1 (-6375 2075)(-6825 2075);
WIRE 16 -1 (-6825 2075)(-6825 2200);
WIRE 16 -1 (-5925 2075)(-6375 2075);
WIRE 16 -1 (-6375 2075)(-6375 2200);
WIRE 16 -1 (-5475 2075)(-5925 2075);
WIRE 16 -1 (-5925 2075)(-5925 2200);
WIRE 16 -1 (-5075 2075)(-5475 2075);
WIRE 16 -1 (-5475 2075)(-5475 2200);
WIRE 16 -1 (-5075 2075)(-5075 2200);
WIRE 16 -1 (-5075 1975)(-5075 2075);
WIRE 16 -1 (-7725 3900)(-8175 3900);
WIRE 16 -1 (-7275 3900)(-7725 3900);
WIRE 16 -1 (-7725 3825)(-7725 3900);
WIRE 16 -1 (-8175 3900)(-8175 3825);
WIRE 16 -1 (-8175 3900)(-8625 3900);
WIRE 16 -1 (-8625 3825)(-8625 3900);
WIRE 16 -1 (-8625 3900)(-9075 3900);
WIRE 16 -1 (-6825 3900)(-7275 3900);
WIRE 16 -1 (-7275 3825)(-7275 3900);
WIRE 16 -1 (-6375 3900)(-6825 3900);
WIRE 16 -1 (-6825 3900)(-6825 3825);
WIRE 16 -1 (-9075 3900)(-9075 3950);
WIRE 16 -1 (-9075 3900)(-9075 3825);
WIRE 16 -1 (-5925 3900)(-6375 3900);
WIRE 16 -1 (-6375 3825)(-6375 3900);
WIRE 16 -1 (-5475 3900)(-5925 3900);
WIRE 16 -1 (-5925 3825)(-5925 3900);
WIRE 16 -1 (-5075 3900)(-5475 3900);
WIRE 16 -1 (-5475 3900)(-5475 3825);
WIRE 16 -1 (-5075 3825)(-5075 3900);
WIRE 16 -1 (-5075 3500)(-5075 3625);
WIRE 16 -1 (-5075 3400)(-5075 3500);
WIRE 16 -1 (-5075 3500)(-5475 3500);
WIRE 16 -1 (-5475 3500)(-5475 3625);
WIRE 16 -1 (-5475 3500)(-5925 3500);
WIRE 16 -1 (-5925 3500)(-5925 3625);
WIRE 16 -1 (-5925 3500)(-6375 3500);
WIRE 16 -1 (-6375 3500)(-6375 3625);
WIRE 16 -1 (-6375 3500)(-6825 3500);
WIRE 16 -1 (-6825 3500)(-6825 3625);
WIRE 16 -1 (-6825 3500)(-7275 3500);
WIRE 16 -1 (-7275 3500)(-7275 3625);
WIRE 16 -1 (-7275 3500)(-7725 3500);
WIRE 16 -1 (-7725 3500)(-7725 3625);
WIRE 16 -1 (-7725 3500)(-8175 3500);
WIRE 16 -1 (-8175 3500)(-8175 3625);
WIRE 16 -1 (-8175 3500)(-8625 3500);
WIRE 16 -1 (-8625 3500)(-8625 3625);
WIRE 16 -1 (-8625 3500)(-9075 3500);
WIRE 16 -1 (-9075 3500)(-9075 3625);
WIRE 16 -1 (-7725 3175)(-8175 3175);
WIRE 16 -1 (-7275 3175)(-7725 3175);
WIRE 16 -1 (-7725 3100)(-7725 3175);
WIRE 16 -1 (-8175 3175)(-8175 3100);
WIRE 16 -1 (-8175 3175)(-8625 3175);
WIRE 16 -1 (-8625 3100)(-8625 3175);
WIRE 16 -1 (-8625 3175)(-9075 3175);
WIRE 16 -1 (-6825 3175)(-7275 3175);
WIRE 16 -1 (-7275 3100)(-7275 3175);
WIRE 16 -1 (-6375 3175)(-6825 3175);
WIRE 16 -1 (-6825 3175)(-6825 3100);
WIRE 16 -1 (-9075 3175)(-9075 3225);
WIRE 16 -1 (-9075 3175)(-9075 3100);
WIRE 16 -1 (-5925 3175)(-6375 3175);
WIRE 16 -1 (-6375 3100)(-6375 3175);
WIRE 16 -1 (-5475 3175)(-5925 3175);
WIRE 16 -1 (-5925 3100)(-5925 3175);
WIRE 16 -1 (-5075 3175)(-5475 3175);
WIRE 16 -1 (-5475 3175)(-5475 3100);
WIRE 16 -1 (-5075 3100)(-5075 3175);
WIRE 16 -1 (-8200 4925)(-8650 4925);
WIRE 16 -1 (-7750 4925)(-8200 4925);
WIRE 16 -1 (-8200 4925)(-8200 5050);
WIRE 16 -1 (-8650 4925)(-8650 5050);
WIRE 16 -1 (-8650 4925)(-9100 4925);
WIRE 16 -1 (-9100 4925)(-9100 5050);
WIRE 16 -1 (-7300 4925)(-7750 4925);
WIRE 16 -1 (-7750 4925)(-7750 5050);
WIRE 16 -1 (-6850 4925)(-7300 4925);
WIRE 16 -1 (-7300 4925)(-7300 5050);
WIRE 16 -1 (-6400 4925)(-6850 4925);
WIRE 16 -1 (-6850 4925)(-6850 5050);
WIRE 16 -1 (-5950 4925)(-6400 4925);
WIRE 16 -1 (-6400 4925)(-6400 5050);
WIRE 16 -1 (-5500 4925)(-5950 4925);
WIRE 16 -1 (-5950 4925)(-5950 5050);
WIRE 16 -1 (-5100 4925)(-5500 4925);
WIRE 16 -1 (-5500 4925)(-5500 5050);
WIRE 16 -1 (-5100 4925)(-5100 5050);
WIRE 16 -1 (-5100 4825)(-5100 4925);
WIRE 16 -1 (-7750 4600)(-8200 4600);
WIRE 16 -1 (-7300 4600)(-7750 4600);
WIRE 16 -1 (-7750 4525)(-7750 4600);
WIRE 16 -1 (-8200 4600)(-8200 4525);
WIRE 16 -1 (-8200 4600)(-8650 4600);
WIRE 16 -1 (-8650 4525)(-8650 4600);
WIRE 16 -1 (-8650 4600)(-9100 4600);
WIRE 16 -1 (-6850 4600)(-7300 4600);
WIRE 16 -1 (-7300 4525)(-7300 4600);
WIRE 16 -1 (-6400 4600)(-6850 4600);
WIRE 16 -1 (-6850 4600)(-6850 4525);
WIRE 16 -1 (-9100 4600)(-9100 4650);
WIRE 16 -1 (-9100 4600)(-9100 4525);
WIRE 16 -1 (-5950 4600)(-6400 4600);
WIRE 16 -1 (-6400 4525)(-6400 4600);
WIRE 16 -1 (-5500 4600)(-5950 4600);
WIRE 16 -1 (-5950 4525)(-5950 4600);
WIRE 16 -1 (-5100 4600)(-5500 4600);
WIRE 16 -1 (-5500 4600)(-5500 4525);
WIRE 16 -1 (-5100 4525)(-5100 4600);
WIRE 16 -1 (-8200 4200)(-8650 4200);
WIRE 16 -1 (-7750 4200)(-8200 4200);
WIRE 16 -1 (-8200 4200)(-8200 4325);
WIRE 16 -1 (-8650 4200)(-8650 4325);
WIRE 16 -1 (-8650 4200)(-9100 4200);
WIRE 16 -1 (-9100 4200)(-9100 4325);
WIRE 16 -1 (-7300 4200)(-7750 4200);
WIRE 16 -1 (-7750 4200)(-7750 4325);
WIRE 16 -1 (-6850 4200)(-7300 4200);
WIRE 16 -1 (-7300 4200)(-7300 4325);
WIRE 16 -1 (-6400 4200)(-6850 4200);
WIRE 16 -1 (-6850 4200)(-6850 4325);
WIRE 16 -1 (-5950 4200)(-6400 4200);
WIRE 16 -1 (-6400 4200)(-6400 4325);
WIRE 16 -1 (-5500 4200)(-5950 4200);
WIRE 16 -1 (-5950 4200)(-5950 4325);
WIRE 16 -1 (-5100 4200)(-5500 4200);
WIRE 16 -1 (-5500 4200)(-5500 4325);
WIRE 16 -1 (-5100 4200)(-5100 4325);
WIRE 16 -1 (-5100 4100)(-5100 4200);
WIRE 16 -1 (-7750 5325)(-8200 5325);
WIRE 16 -1 (-7300 5325)(-7750 5325);
WIRE 16 -1 (-7750 5250)(-7750 5325);
WIRE 16 -1 (-8200 5325)(-8200 5250);
WIRE 16 -1 (-8200 5325)(-8650 5325);
WIRE 16 -1 (-8650 5250)(-8650 5325);
WIRE 16 -1 (-8650 5325)(-9100 5325);
WIRE 16 -1 (-6850 5325)(-7300 5325);
WIRE 16 -1 (-7300 5250)(-7300 5325);
WIRE 16 -1 (-6400 5325)(-6850 5325);
WIRE 16 -1 (-6850 5325)(-6850 5250);
WIRE 16 -1 (-9100 5325)(-9100 5250);
WIRE 16 -1 (-9100 5325)(-9100 5375);
WIRE 16 -1 (-5950 5325)(-6400 5325);
WIRE 16 -1 (-6400 5250)(-6400 5325);
WIRE 16 -1 (-5500 5325)(-5950 5325);
WIRE 16 -1 (-5950 5250)(-5950 5325);
WIRE 16 -1 (-5100 5325)(-5500 5325);
WIRE 16 -1 (-5500 5325)(-5500 5250);
WIRE 16 -1 (-5100 5250)(-5100 5325);
WIRE 16 -1 (-7750 6075)(-8200 6075);
WIRE 16 -1 (-7300 6075)(-7750 6075);
WIRE 16 -1 (-7750 6000)(-7750 6075);
WIRE 16 -1 (-8200 6075)(-8200 6000);
WIRE 16 -1 (-8200 6075)(-8650 6075);
WIRE 16 -1 (-8650 6000)(-8650 6075);
WIRE 16 -1 (-8650 6075)(-9100 6075);
WIRE 16 -1 (-6850 6075)(-7300 6075);
WIRE 16 -1 (-7300 6000)(-7300 6075);
WIRE 16 -1 (-6400 6075)(-6850 6075);
WIRE 16 -1 (-6850 6075)(-6850 6000);
WIRE 16 -1 (-9100 6075)(-9100 6000);
WIRE 16 -1 (-9100 6075)(-9100 6125);
WIRE 16 -1 (-5950 6075)(-6400 6075);
WIRE 16 -1 (-6400 6000)(-6400 6075);
WIRE 16 -1 (-5500 6075)(-5950 6075);
WIRE 16 -1 (-5950 6000)(-5950 6075);
WIRE 16 -1 (-5100 6075)(-5500 6075);
WIRE 16 -1 (-5500 6075)(-5500 6000);
WIRE 16 -1 (-5100 6000)(-5100 6075);
WIRE 16 -1 (-8200 5675)(-8650 5675);
WIRE 16 -1 (-7750 5675)(-8200 5675);
WIRE 16 -1 (-8200 5675)(-8200 5800);
WIRE 16 -1 (-8650 5675)(-8650 5800);
WIRE 16 -1 (-8650 5675)(-9100 5675);
WIRE 16 -1 (-9100 5675)(-9100 5800);
WIRE 16 -1 (-7300 5675)(-7750 5675);
WIRE 16 -1 (-7750 5675)(-7750 5800);
WIRE 16 -1 (-6850 5675)(-7300 5675);
WIRE 16 -1 (-7300 5675)(-7300 5800);
WIRE 16 -1 (-6400 5675)(-6850 5675);
WIRE 16 -1 (-6850 5675)(-6850 5800);
WIRE 16 -1 (-5950 5675)(-6400 5675);
WIRE 16 -1 (-6400 5675)(-6400 5800);
WIRE 16 -1 (-5500 5675)(-5950 5675);
WIRE 16 -1 (-5950 5675)(-5950 5800);
WIRE 16 -1 (-5100 5675)(-5500 5675);
WIRE 16 -1 (-5500 5675)(-5500 5800);
WIRE 16 -1 (-5100 5675)(-5100 5800);
WIRE 16 -1 (-5100 5575)(-5100 5675);
WIRE 16 3135 (-9275 6550)(-4725 6550);
WIRE 16 3135 (-9275 450)(-9275 6550);
WIRE 16 3135 (-4725 450)(-4725 6550);
WIRE 16 3135 (-9275 450)(-4725 450);
WIRE 16 -1 (-3150 3450)(-3600 3450);
WIRE 16 -1 (-2700 3450)(-3150 3450);
WIRE 16 -1 (-3150 3375)(-3150 3450);
WIRE 16 -1 (-3600 3450)(-3600 3375);
WIRE 16 -1 (-3600 3450)(-4050 3450);
WIRE 16 -1 (-4050 3375)(-4050 3450);
WIRE 16 -1 (-4050 3450)(-4500 3450);
WIRE 16 -1 (-2250 3450)(-2700 3450);
WIRE 16 -1 (-2700 3375)(-2700 3450);
WIRE 16 -1 (-1800 3450)(-2250 3450);
WIRE 16 -1 (-2250 3450)(-2250 3375);
WIRE 16 -1 (-4500 3450)(-4500 3500);
WIRE 16 -1 (-4500 3450)(-4500 3375);
WIRE 16 -1 (-1350 3450)(-1800 3450);
WIRE 16 -1 (-1800 3375)(-1800 3450);
WIRE 16 -1 (-900 3450)(-1350 3450);
WIRE 16 -1 (-1350 3375)(-1350 3450);
WIRE 16 -1 (-500 3450)(-900 3450);
WIRE 16 -1 (-900 3450)(-900 3375);
WIRE 16 -1 (-500 3375)(-500 3450);
WIRE 16 -1 (-500 3050)(-500 3175);
WIRE 16 -1 (-500 2950)(-500 3050);
WIRE 16 -1 (-500 3050)(-900 3050);
WIRE 16 -1 (-900 3050)(-900 3175);
WIRE 16 -1 (-900 3050)(-1350 3050);
WIRE 16 -1 (-1350 3050)(-1350 3175);
WIRE 16 -1 (-1350 3050)(-1800 3050);
WIRE 16 -1 (-1800 3050)(-1800 3175);
WIRE 16 -1 (-1800 3050)(-2250 3050);
WIRE 16 -1 (-2250 3050)(-2250 3175);
WIRE 16 -1 (-2250 3050)(-2700 3050);
WIRE 16 -1 (-2700 3050)(-2700 3175);
WIRE 16 -1 (-2700 3050)(-3150 3050);
WIRE 16 -1 (-3150 3050)(-3150 3175);
WIRE 16 -1 (-3150 3050)(-3600 3050);
WIRE 16 -1 (-3600 3050)(-3600 3175);
WIRE 16 -1 (-3600 3050)(-4050 3050);
WIRE 16 -1 (-4050 3050)(-4050 3175);
WIRE 16 -1 (-4050 3050)(-4500 3050);
WIRE 16 -1 (-4500 3050)(-4500 3175);
WIRE 16 -1 (-3150 2800)(-3600 2800);
WIRE 16 -1 (-2700 2800)(-3150 2800);
WIRE 16 -1 (-3150 2725)(-3150 2800);
WIRE 16 -1 (-3600 2800)(-3600 2725);
WIRE 16 -1 (-3600 2800)(-4050 2800);
WIRE 16 -1 (-4050 2725)(-4050 2800);
WIRE 16 -1 (-4050 2800)(-4500 2800);
WIRE 16 -1 (-2250 2800)(-2700 2800);
WIRE 16 -1 (-2700 2725)(-2700 2800);
WIRE 16 -1 (-1800 2800)(-2250 2800);
WIRE 16 -1 (-2250 2800)(-2250 2725);
WIRE 16 -1 (-4500 2800)(-4500 2850);
WIRE 16 -1 (-4500 2800)(-4500 2725);
WIRE 16 -1 (-1350 2800)(-1800 2800);
WIRE 16 -1 (-1800 2725)(-1800 2800);
WIRE 16 -1 (-900 2800)(-1350 2800);
WIRE 16 -1 (-1350 2725)(-1350 2800);
WIRE 16 -1 (-500 2800)(-900 2800);
WIRE 16 -1 (-900 2800)(-900 2725);
WIRE 16 -1 (-500 2725)(-500 2800);
WIRE 16 -1 (-3600 2400)(-4050 2400);
WIRE 16 -1 (-3150 2400)(-3600 2400);
WIRE 16 -1 (-3600 2400)(-3600 2525);
WIRE 16 -1 (-4050 2400)(-4050 2525);
WIRE 16 -1 (-4050 2400)(-4500 2400);
WIRE 16 -1 (-4500 2400)(-4500 2525);
WIRE 16 -1 (-2700 2400)(-3150 2400);
WIRE 16 -1 (-3150 2400)(-3150 2525);
WIRE 16 -1 (-2250 2400)(-2700 2400);
WIRE 16 -1 (-2700 2400)(-2700 2525);
WIRE 16 -1 (-1800 2400)(-2250 2400);
WIRE 16 -1 (-2250 2400)(-2250 2525);
WIRE 16 -1 (-1350 2400)(-1800 2400);
WIRE 16 -1 (-1800 2400)(-1800 2525);
WIRE 16 -1 (-900 2400)(-1350 2400);
WIRE 16 -1 (-1350 2400)(-1350 2525);
WIRE 16 -1 (-500 2400)(-900 2400);
WIRE 16 -1 (-900 2400)(-900 2525);
WIRE 16 -1 (-500 2400)(-500 2525);
WIRE 16 -1 (-500 2325)(-500 2400);
WIRE 16 -1 (-3150 2175)(-3600 2175);
WIRE 16 -1 (-2700 2175)(-3150 2175);
WIRE 16 -1 (-3150 2100)(-3150 2175);
WIRE 16 -1 (-3600 2175)(-3600 2100);
WIRE 16 -1 (-3600 2175)(-4050 2175);
WIRE 16 -1 (-4050 2100)(-4050 2175);
WIRE 16 -1 (-4050 2175)(-4500 2175);
WIRE 16 -1 (-2250 2175)(-2700 2175);
WIRE 16 -1 (-2700 2100)(-2700 2175);
WIRE 16 -1 (-1800 2175)(-2250 2175);
WIRE 16 -1 (-2250 2175)(-2250 2100);
WIRE 16 -1 (-4500 2175)(-4500 2225);
WIRE 16 -1 (-4500 2175)(-4500 2100);
WIRE 16 -1 (-1350 2175)(-1800 2175);
WIRE 16 -1 (-1800 2100)(-1800 2175);
WIRE 16 -1 (-900 2175)(-1350 2175);
WIRE 16 -1 (-1350 2100)(-1350 2175);
WIRE 16 -1 (-500 2175)(-900 2175);
WIRE 16 -1 (-900 2175)(-900 2100);
WIRE 16 -1 (-500 2100)(-500 2175);
WIRE 16 -1 (-3600 1775)(-4050 1775);
WIRE 16 -1 (-3150 1775)(-3600 1775);
WIRE 16 -1 (-3600 1775)(-3600 1900);
WIRE 16 -1 (-4050 1775)(-4050 1900);
WIRE 16 -1 (-4050 1775)(-4500 1775);
WIRE 16 -1 (-4500 1775)(-4500 1900);
WIRE 16 -1 (-2700 1775)(-3150 1775);
WIRE 16 -1 (-3150 1775)(-3150 1900);
WIRE 16 -1 (-2250 1775)(-2700 1775);
WIRE 16 -1 (-2700 1775)(-2700 1900);
WIRE 16 -1 (-1800 1775)(-2250 1775);
WIRE 16 -1 (-2250 1775)(-2250 1900);
WIRE 16 -1 (-1350 1775)(-1800 1775);
WIRE 16 -1 (-1800 1775)(-1800 1900);
WIRE 16 -1 (-900 1775)(-1350 1775);
WIRE 16 -1 (-1350 1775)(-1350 1900);
WIRE 16 -1 (-500 1775)(-900 1775);
WIRE 16 -1 (-900 1775)(-900 1900);
WIRE 16 -1 (-500 1775)(-500 1900);
WIRE 16 -1 (-500 1675)(-500 1775);
WIRE 16 -1 (-3150 1575)(-3600 1575);
WIRE 16 -1 (-2700 1575)(-3150 1575);
WIRE 16 -1 (-3150 1500)(-3150 1575);
WIRE 16 -1 (-3600 1575)(-4050 1575);
WIRE 16 -1 (-3600 1575)(-3600 1500);
WIRE 16 -1 (-4050 1500)(-4050 1575);
WIRE 16 -1 (-4050 1575)(-4500 1575);
WIRE 16 -1 (-2250 1575)(-2700 1575);
WIRE 16 -1 (-2700 1500)(-2700 1575);
WIRE 16 -1 (-1800 1575)(-2250 1575);
WIRE 16 -1 (-2250 1575)(-2250 1500);
WIRE 16 -1 (-4500 1575)(-4500 1625);
WIRE 16 -1 (-4500 1575)(-4500 1500);
WIRE 16 -1 (-1350 1575)(-1800 1575);
WIRE 16 -1 (-1800 1500)(-1800 1575);
WIRE 16 -1 (-900 1575)(-1350 1575);
WIRE 16 -1 (-1350 1500)(-1350 1575);
WIRE 16 -1 (-500 1575)(-900 1575);
WIRE 16 -1 (-900 1575)(-900 1500);
WIRE 16 -1 (-500 1500)(-500 1575);
WIRE 16 -1 (-3600 1175)(-4050 1175);
WIRE 16 -1 (-3150 1175)(-3600 1175);
WIRE 16 -1 (-3600 1175)(-3600 1300);
WIRE 16 -1 (-4050 1175)(-4050 1300);
WIRE 16 -1 (-4050 1175)(-4500 1175);
WIRE 16 -1 (-4500 1175)(-4500 1300);
WIRE 16 -1 (-2700 1175)(-3150 1175);
WIRE 16 -1 (-3150 1175)(-3150 1300);
WIRE 16 -1 (-2250 1175)(-2700 1175);
WIRE 16 -1 (-2700 1175)(-2700 1300);
WIRE 16 -1 (-1800 1175)(-2250 1175);
WIRE 16 -1 (-2250 1175)(-2250 1300);
WIRE 16 -1 (-1350 1175)(-1800 1175);
WIRE 16 -1 (-1800 1175)(-1800 1300);
WIRE 16 -1 (-900 1175)(-1350 1175);
WIRE 16 -1 (-1350 1300)(-1350 1175);
WIRE 16 -1 (-500 1175)(-900 1175);
WIRE 16 -1 (-900 1175)(-900 1300);
WIRE 16 -1 (-500 1175)(-500 1300);
WIRE 16 -1 (-500 1075)(-500 1175);
WIRE 16 -1 (-4050 900)(-4050 975);
WIRE 16 -1 (-4050 975)(-4500 975);
WIRE 16 -1 (-4500 975)(-4500 1025);
WIRE 16 -1 (-4500 975)(-4500 900);
WIRE 16 -1 (-4050 575)(-4050 700);
WIRE 16 -1 (-4050 525)(-4050 575);
WIRE 16 -1 (-4050 575)(-4500 575);
WIRE 16 -1 (-4500 575)(-4500 700);
WIRE 16 -1 (-3175 5275)(-3625 5275);
WIRE 16 -1 (-2725 5275)(-3175 5275);
WIRE 16 -1 (-3175 5200)(-3175 5275);
WIRE 16 -1 (-3625 5275)(-3625 5200);
WIRE 16 -1 (-3625 5275)(-4075 5275);
WIRE 16 -1 (-4075 5200)(-4075 5275);
WIRE 16 -1 (-4075 5275)(-4525 5275);
WIRE 16 -1 (-2275 5275)(-2725 5275);
WIRE 16 -1 (-2725 5200)(-2725 5275);
WIRE 16 -1 (-1825 5275)(-2275 5275);
WIRE 16 -1 (-2275 5275)(-2275 5200);
WIRE 16 -1 (-4525 5275)(-4525 5200);
WIRE 16 -1 (-4525 5275)(-4525 5325);
WIRE 16 -1 (-1375 5275)(-1825 5275);
WIRE 16 -1 (-1825 5200)(-1825 5275);
WIRE 16 -1 (-925 5275)(-1375 5275);
WIRE 16 -1 (-1375 5200)(-1375 5275);
WIRE 16 -1 (-525 5275)(-925 5275);
WIRE 16 -1 (-925 5275)(-925 5200);
WIRE 16 -1 (-525 5200)(-525 5275);
WIRE 16 -1 (-3625 4875)(-4075 4875);
WIRE 16 -1 (-3175 4875)(-3625 4875);
WIRE 16 -1 (-3625 4875)(-3625 5000);
WIRE 16 -1 (-4075 4875)(-4075 5000);
WIRE 16 -1 (-4075 4875)(-4525 4875);
WIRE 16 -1 (-4525 4875)(-4525 5000);
WIRE 16 -1 (-2725 4875)(-3175 4875);
WIRE 16 -1 (-3175 4875)(-3175 5000);
WIRE 16 -1 (-2275 4875)(-2725 4875);
WIRE 16 -1 (-2725 4875)(-2725 5000);
WIRE 16 -1 (-1825 4875)(-2275 4875);
WIRE 16 -1 (-2275 4875)(-2275 5000);
WIRE 16 -1 (-1375 4875)(-1825 4875);
WIRE 16 -1 (-1825 4875)(-1825 5000);
WIRE 16 -1 (-925 4875)(-1375 4875);
WIRE 16 -1 (-1375 4875)(-1375 5000);
WIRE 16 -1 (-525 4875)(-925 4875);
WIRE 16 -1 (-925 4875)(-925 5000);
WIRE 16 -1 (-525 4875)(-525 5000);
WIRE 16 -1 (-525 4775)(-525 4875);
WIRE 16 -1 (-3175 6075)(-3625 6075);
WIRE 16 -1 (-2725 6075)(-3175 6075);
WIRE 16 -1 (-3175 6000)(-3175 6075);
WIRE 16 -1 (-3625 6075)(-3625 6000);
WIRE 16 -1 (-3625 6075)(-4075 6075);
WIRE 16 -1 (-4075 6000)(-4075 6075);
WIRE 16 -1 (-4075 6075)(-4525 6075);
WIRE 16 -1 (-2275 6075)(-2725 6075);
WIRE 16 -1 (-2725 6000)(-2725 6075);
WIRE 16 -1 (-1825 6075)(-2275 6075);
WIRE 16 -1 (-2275 6075)(-2275 6000);
WIRE 16 -1 (-4525 6075)(-4525 6000);
WIRE 16 -1 (-4525 6075)(-4525 6125);
WIRE 16 -1 (-1375 6075)(-1825 6075);
WIRE 16 -1 (-1825 6000)(-1825 6075);
WIRE 16 -1 (-925 6075)(-1375 6075);
WIRE 16 -1 (-1375 6000)(-1375 6075);
WIRE 16 -1 (-525 6075)(-925 6075);
WIRE 16 -1 (-925 6075)(-925 6000);
WIRE 16 -1 (-525 6000)(-525 6075);
WIRE 16 -1 (-3625 5675)(-4075 5675);
WIRE 16 -1 (-3175 5675)(-3625 5675);
WIRE 16 -1 (-3625 5675)(-3625 5800);
WIRE 16 -1 (-4075 5675)(-4075 5800);
WIRE 16 -1 (-4075 5675)(-4525 5675);
WIRE 16 -1 (-4525 5675)(-4525 5800);
WIRE 16 -1 (-2725 5675)(-3175 5675);
WIRE 16 -1 (-3175 5675)(-3175 5800);
WIRE 16 -1 (-2275 5675)(-2725 5675);
WIRE 16 -1 (-2725 5675)(-2725 5800);
WIRE 16 -1 (-1825 5675)(-2275 5675);
WIRE 16 -1 (-2275 5675)(-2275 5800);
WIRE 16 -1 (-1375 5675)(-1825 5675);
WIRE 16 -1 (-1825 5675)(-1825 5800);
WIRE 16 -1 (-925 5675)(-1375 5675);
WIRE 16 -1 (-1375 5675)(-1375 5800);
WIRE 16 -1 (-525 5675)(-925 5675);
WIRE 16 -1 (-925 5675)(-925 5800);
WIRE 16 -1 (-525 5675)(-525 5800);
WIRE 16 -1 (-525 5575)(-525 5675);
WIRE 16 -1 (-3150 4500)(-3600 4500);
WIRE 16 -1 (-3150 4425)(-3150 4500);
WIRE 16 -1 (-3600 4500)(-3600 4425);
WIRE 16 -1 (-3600 4500)(-4050 4500);
WIRE 16 -1 (-4050 4425)(-4050 4500);
WIRE 16 -1 (-4050 4500)(-4500 4500);
WIRE 16 -1 (-4500 4500)(-4500 4425);
WIRE 16 -1 (-4500 4500)(-4500 4550);
WIRE 16 -1 (-3600 4100)(-4050 4100);
WIRE 16 -1 (-3150 4100)(-3600 4100);
WIRE 16 -1 (-3600 4100)(-3600 4225);
WIRE 16 -1 (-4050 4100)(-4050 4225);
WIRE 16 -1 (-4050 4100)(-4500 4100);
WIRE 16 -1 (-4500 4100)(-4500 4225);
WIRE 16 -1 (-3150 4100)(-3150 4225);
WIRE 16 -1 (-3150 4000)(-3150 4100);
WIRE 16 3135 (-4650 6500)(-200 6500);
WIRE 16 3135 (-4650 3825)(-4650 6500);
WIRE 16 3135 (-200 3825)(-200 6500);
WIRE 16 3135 (-4650 3825)(-200 3825);
DOT 1 (-8650 4600);
DOT 1 (-4050 2175);
DOT 1 (-3600 3450);
DOT 1 (-9075 1050);
DOT 1 (-8625 650);
DOT 1 (-8625 1050);
DOT 1 (-9075 1750);
DOT 1 (-8625 1350);
DOT 1 (-8625 1750);
DOT 1 (-8625 2075);
DOT 1 (-9075 2475);
DOT 1 (-8625 2475);
DOT 1 (-8625 2775);
DOT 1 (-8625 3175);
DOT 1 (-9075 3175);
DOT 1 (-9075 3900);
DOT 1 (-8625 3500);
DOT 1 (-8625 3900);
DOT 1 (-8650 4200);
DOT 1 (-9100 4600);
DOT 1 (-8650 4925);
DOT 1 (-9100 5325);
DOT 1 (-9100 6075);
DOT 1 (-8650 5325);
DOT 1 (-8650 5675);
DOT 1 (-8650 6075);
DOT 1 (-8175 650);
DOT 1 (-8175 1050);
DOT 1 (-7725 650);
DOT 1 (-7725 1050);
DOT 1 (-7275 650);
DOT 1 (-7275 1050);
DOT 1 (-8175 1350);
DOT 1 (-8175 1750);
DOT 1 (-8175 2075);
DOT 1 (-7725 1350);
DOT 1 (-7275 1350);
DOT 1 (-7725 1750);
DOT 1 (-7725 2075);
DOT 1 (-7275 2075);
DOT 1 (-7275 1750);
DOT 1 (-6825 650);
DOT 1 (-6825 1050);
DOT 1 (-6375 650);
DOT 1 (-6825 1350);
DOT 1 (-6825 1750);
DOT 1 (-6825 2075);
DOT 1 (-6375 1350);
DOT 1 (-6375 1750);
DOT 1 (-6375 2075);
DOT 1 (-8175 2475);
DOT 1 (-8175 2775);
DOT 1 (-7725 2475);
DOT 1 (-7275 2475);
DOT 1 (-7725 2775);
DOT 1 (-7275 2775);
DOT 1 (-7275 3175);
DOT 1 (-7725 3175);
DOT 1 (-8175 3175);
DOT 1 (-8175 3500);
DOT 1 (-8175 3900);
DOT 1 (-7725 3500);
DOT 1 (-7275 3500);
DOT 1 (-7725 3900);
DOT 1 (-7275 3900);
DOT 1 (-6825 2475);
DOT 1 (-6825 2775);
DOT 1 (-6375 2475);
DOT 1 (-6375 2775);
DOT 1 (-6375 3175);
DOT 1 (-6825 3175);
DOT 1 (-6825 3500);
DOT 1 (-6825 3900);
DOT 1 (-6375 3500);
DOT 1 (-6375 3900);
DOT 1 (-5925 1350);
DOT 1 (-5925 1750);
DOT 1 (-5925 2075);
DOT 1 (-5475 1350);
DOT 1 (-5475 1750);
DOT 1 (-5475 2075);
DOT 1 (-4500 975);
DOT 1 (-5075 1350);
DOT 1 (-5075 2075);
DOT 1 (-4500 1575);
DOT 1 (-5925 2475);
DOT 1 (-5925 2775);
DOT 1 (-5475 2475);
DOT 1 (-5475 2775);
DOT 1 (-5475 3175);
DOT 1 (-5925 3175);
DOT 1 (-5925 3500);
DOT 1 (-5925 3900);
DOT 1 (-5475 3500);
DOT 1 (-5475 3900);
DOT 1 (-5075 2775);
DOT 1 (-4500 2175);
DOT 1 (-4500 2800);
DOT 1 (-5075 3500);
DOT 1 (-4500 3450);
DOT 1 (-5100 4200);
DOT 1 (-5500 4200);
DOT 1 (-5950 4200);
DOT 1 (-6400 4200);
DOT 1 (-6850 4200);
DOT 1 (-7300 4200);
DOT 1 (-7750 4200);
DOT 1 (-8200 4200);
DOT 1 (-8200 4600);
DOT 1 (-8200 4925);
DOT 1 (-7750 4600);
DOT 1 (-7300 4600);
DOT 1 (-7750 4925);
DOT 1 (-7300 4925);
DOT 1 (-8200 5325);
DOT 1 (-8200 5675);
DOT 1 (-8200 6075);
DOT 1 (-7750 5325);
DOT 1 (-7750 5675);
DOT 1 (-7300 5325);
DOT 1 (-7300 5675);
DOT 1 (-7750 6075);
DOT 1 (-7300 6075);
DOT 1 (-6850 4600);
DOT 1 (-6850 4925);
DOT 1 (-6400 4600);
DOT 1 (-6400 4925);
DOT 1 (-6850 5325);
DOT 1 (-6850 5675);
DOT 1 (-6850 6075);
DOT 1 (-6400 5325);
DOT 1 (-6400 5675);
DOT 1 (-6400 6075);
DOT 1 (-5950 4600);
DOT 1 (-5950 4925);
DOT 1 (-5500 4600);
DOT 1 (-5500 4925);
DOT 1 (-5950 5675);
DOT 1 (-5950 6075);
DOT 1 (-5500 5325);
DOT 1 (-5500 5675);
DOT 1 (-5500 6075);
DOT 1 (-5100 4925);
DOT 1 (-4500 4500);
DOT 1 (-5100 5675);
DOT 1 (-4525 5275);
DOT 1 (-4525 6075);
DOT 1 (-4050 575);
DOT 1 (-4050 1175);
DOT 1 (-4050 1575);
DOT 1 (-4050 1775);
DOT 1 (-3600 1175);
DOT 1 (-3600 1575);
DOT 1 (-3600 1775);
DOT 1 (-3150 1175);
DOT 1 (-3150 1575);
DOT 1 (-2700 1175);
DOT 1 (-2700 1575);
DOT 1 (-3150 1775);
DOT 1 (-2700 1775);
DOT 1 (-2250 1175);
DOT 1 (-2250 1575);
DOT 1 (-2250 1775);
DOT 1 (-4050 2400);
DOT 1 (-4050 2800);
DOT 1 (-4050 3050);
DOT 1 (-3600 2400);
DOT 1 (-3600 2175);
DOT 1 (-3600 2800);
DOT 1 (-3600 3050);
DOT 1 (-4050 3450);
DOT 1 (-4050 4100);
DOT 1 (-3600 4100);
DOT 1 (-3150 2175);
DOT 1 (-3150 2400);
DOT 1 (-2700 2175);
DOT 1 (-2700 2400);
DOT 1 (-3150 2800);
DOT 1 (-3150 3050);
DOT 1 (-2700 2800);
DOT 1 (-2700 3050);
DOT 1 (-2250 2175);
DOT 1 (-2250 2400);
DOT 1 (-2250 2800);
DOT 1 (-2250 3050);
DOT 1 (-3150 3450);
DOT 1 (-2700 3450);
DOT 1 (-3150 4100);
DOT 1 (-2250 3450);
DOT 1 (-1800 1175);
DOT 1 (-1800 1575);
DOT 1 (-1800 1775);
DOT 1 (-1350 1175);
DOT 1 (-1350 1575);
DOT 1 (-1350 1775);
DOT 1 (-900 1175);
DOT 1 (-900 1575);
DOT 1 (-900 1775);
DOT 1 (-500 1175);
DOT 1 (-500 1775);
DOT 1 (-1800 2400);
DOT 1 (-1800 2175);
DOT 1 (-1800 2800);
DOT 1 (-1800 3050);
DOT 1 (-1350 2175);
DOT 1 (-1350 2400);
DOT 1 (-1350 2800);
DOT 1 (-1350 3050);
DOT 1 (-1800 3450);
DOT 1 (-1350 3450);
DOT 1 (-900 2175);
DOT 1 (-900 2400);
DOT 1 (-900 2800);
DOT 1 (-900 3050);
DOT 1 (-500 2400);
DOT 1 (-500 3050);
DOT 1 (-900 3450);
DOT 1 (-4050 4500);
DOT 1 (-4075 4875);
DOT 1 (-3600 4500);
DOT 1 (-3625 4875);
DOT 1 (-3175 4875);
DOT 1 (-4075 5275);
DOT 1 (-4075 5675);
DOT 1 (-4075 6075);
DOT 1 (-3625 5275);
DOT 1 (-3625 5675);
DOT 1 (-3175 5275);
DOT 1 (-3175 5675);
DOT 1 (-3625 6075);
DOT 1 (-3175 6075);
DOT 1 (-2725 4875);
DOT 1 (-2275 4875);
DOT 1 (-2725 5275);
DOT 1 (-2725 5675);
DOT 1 (-2725 6075);
DOT 1 (-2275 5275);
DOT 1 (-2275 5675);
DOT 1 (-2275 6075);
DOT 1 (-1825 4875);
DOT 1 (-1375 4875);
DOT 1 (-1825 5275);
DOT 1 (-1825 5675);
DOT 1 (-1825 6075);
DOT 1 (-1375 5275);
DOT 1 (-1375 5675);
DOT 1 (-1375 6075);
DOT 1 (-925 4875);
DOT 1 (-525 4875);
DOT 1 (-925 5275);
DOT 1 (-925 5675);
DOT 1 (-925 6075);
DOT 1 (-525 5675);
DOT 1 (-5950 5325);
FORCENOTE
PVDD11_S3_P0: 42PCS 22UF ON BOT
(-4200 3575) 0;
DISPLAY LEFT (-4200 3575);
DISPLAY 2.510638 (-4200 3575);
PAINT WHITE (-4200 3575);
FORCENOTE
5
(-2725 3475) 0;
DISPLAY LEFT (-2725 3475);
DISPLAY 1.021277 (-2725 3475);
PAINT SKYBLUE (-2725 3475);
FORCENOTE
PVDDCR_SOC_P0: 77PCS 22UF ON BOT
(-9175 6325) 0;
DISPLAY LEFT (-9175 6325);
DISPLAY 2.510638 (-9175 6325);
PAINT WHITE (-9175 6325);
FORCENOTE
5
(-7300 1100) 0;
DISPLAY LEFT (-7300 1100);
DISPLAY 1.021277 (-7300 1100);
PAINT SKYBLUE (-7300 1100);
FORCENOTE
5
(-7300 1800) 0;
DISPLAY LEFT (-7300 1800);
DISPLAY 1.021277 (-7300 1800);
PAINT SKYBLUE (-7300 1800);
FORCENOTE
5
(-7300 3200) 0;
DISPLAY LEFT (-7300 3200);
DISPLAY 1.021277 (-7300 3200);
PAINT SKYBLUE (-7300 3200);
FORCENOTE
5
(-7300 3925) 0;
DISPLAY LEFT (-7300 3925);
DISPLAY 1.021277 (-7300 3925);
PAINT SKYBLUE (-7300 3925);
FORCENOTE
5
(-7300 2525) 0;
DISPLAY LEFT (-7300 2525);
DISPLAY 1.021277 (-7300 2525);
PAINT SKYBLUE (-7300 2525);
FORCENOTE
10
(-5125 1800) 0;
DISPLAY LEFT (-5125 1800);
DISPLAY 1.021277 (-5125 1800);
PAINT SKYBLUE (-5125 1800);
FORCENOTE
10
(-5125 2525) 0;
DISPLAY LEFT (-5125 2525);
DISPLAY 1.021277 (-5125 2525);
PAINT SKYBLUE (-5125 2525);
FORCENOTE
10
(-5100 3200) 0;
DISPLAY LEFT (-5100 3200);
DISPLAY 1.021277 (-5100 3200);
PAINT SKYBLUE (-5100 3200);
FORCENOTE
10
(-5125 3925) 0;
DISPLAY LEFT (-5125 3925);
DISPLAY 1.021277 (-5125 3925);
PAINT SKYBLUE (-5125 3925);
FORCENOTE
5
(-7325 4650) 0;
DISPLAY LEFT (-7325 4650);
DISPLAY 1.021277 (-7325 4650);
PAINT SKYBLUE (-7325 4650);
FORCENOTE
5
(-7325 6125) 0;
DISPLAY LEFT (-7325 6125);
DISPLAY 1.021277 (-7325 6125);
PAINT SKYBLUE (-7325 6125);
FORCENOTE
10
(-5150 4625) 0;
DISPLAY LEFT (-5150 4625);
DISPLAY 1.021277 (-5150 4625);
PAINT SKYBLUE (-5150 4625);
FORCENOTE
10
(-5150 6100) 0;
DISPLAY LEFT (-5150 6100);
DISPLAY 1.021277 (-5150 6100);
PAINT SKYBLUE (-5150 6100);
FORCENOTE
PVDDIO_P0: 24PCS 22UF ON BOT
(-4550 6325) 0;
DISPLAY LEFT (-4550 6325);
DISPLAY 2.510638 (-4550 6325);
PAINT WHITE (-4550 6325);
FORCENOTE
5
(-2725 1625) 0;
DISPLAY LEFT (-2725 1625);
DISPLAY 1.021277 (-2725 1625);
PAINT SKYBLUE (-2725 1625);
FORCENOTE
5
(-2725 2225) 0;
DISPLAY LEFT (-2725 2225);
DISPLAY 1.021277 (-2725 2225);
PAINT SKYBLUE (-2725 2225);
FORCENOTE
5
(-2725 2825) 0;
DISPLAY LEFT (-2725 2825);
DISPLAY 1.021277 (-2725 2825);
PAINT SKYBLUE (-2725 2825);
FORCENOTE
10
(-650 1600) 0;
DISPLAY LEFT (-650 1600);
DISPLAY 1.021277 (-650 1600);
PAINT SKYBLUE (-650 1600);
FORCENOTE
10
(-550 2200) 0;
DISPLAY LEFT (-550 2200);
DISPLAY 1.021277 (-550 2200);
PAINT SKYBLUE (-550 2200);
FORCENOTE
10
(-550 2825) 0;
DISPLAY LEFT (-550 2825);
DISPLAY 1.021277 (-550 2825);
PAINT SKYBLUE (-550 2825);
FORCENOTE
10
(-525 3475) 0;
DISPLAY LEFT (-525 3475);
DISPLAY 1.021277 (-525 3475);
PAINT SKYBLUE (-525 3475);
FORCENOTE
5
(-2750 5375) 0;
DISPLAY LEFT (-2750 5375);
DISPLAY 1.021277 (-2750 5375);
PAINT SKYBLUE (-2750 5375);
FORCENOTE
5
(-2750 6175) 0;
DISPLAY LEFT (-2750 6175);
DISPLAY 1.021277 (-2750 6175);
PAINT SKYBLUE (-2750 6175);
FORCENOTE
10
(-575 6175) 0;
DISPLAY LEFT (-575 6175);
DISPLAY 1.021277 (-575 6175);
PAINT SKYBLUE (-575 6175);
FORCENOTE
10
(-575 5375) 0;
DISPLAY LEFT (-575 5375);
DISPLAY 1.021277 (-575 5375);
PAINT SKYBLUE (-575 5375);
FORCENOTE
10
(-5150 5350) 0;
DISPLAY LEFT (-5150 5350);
DISPLAY 1.021277 (-5150 5350);
PAINT SKYBLUE (-5150 5350);
FORCENOTE
5
(-7325 5375) 0;
DISPLAY LEFT (-7325 5375);
DISPLAY 1.021277 (-7325 5375);
PAINT SKYBLUE (-7325 5375);
QUIT
